(kicad_sch
	(version 20231120)
	(generator "eeschema")
	(generator_version "8.0")
	(paper "A3")
	(title_block
		(title "Jetson Orin Baseboard")
		(date "2025-03-12")
		(rev "1.3.4")
		(company "Antmicro Ltd")
		(comment 1 "www.antmicro.com")
	)
	(junction
		(at 143.51 165.1)
		(diameter 0)
		(color 0 0 0 0)
	)
	(junction
		(at 71.12 118.11)
		(diameter 0)
		(color 0 0 0 0)
	)
	(junction
		(at 299.72 193.04)
		(diameter 0)
		(color 0 0 0 0)
	)
	(junction
		(at 236.22 49.53)
		(diameter 0)
		(color 0 0 0 0)
	)
	(junction
		(at 43.18 45.72)
		(diameter 0)
		(color 0 0 0 0)
	)
	(junction
		(at 60.96 39.37)
		(diameter 0)
		(color 0 0 0 0)
	)
	(junction
		(at 153.67 262.89)
		(diameter 0)
		(color 0 0 0 0)
	)
	(junction
		(at 214.63 139.7)
		(diameter 0)
		(color 0 0 0 0)
	)
	(junction
		(at 43.18 33.02)
		(diameter 0)
		(color 0 0 0 0)
	)
	(junction
		(at 207.01 187.96)
		(diameter 0)
		(color 0 0 0 0)
	)
	(junction
		(at 355.6 30.48)
		(diameter 0)
		(color 0 0 0 0)
	)
	(junction
		(at 156.21 165.1)
		(diameter 0)
		(color 0 0 0 0)
	)
	(junction
		(at 203.2 262.89)
		(diameter 0)
		(color 0 0 0 0)
	)
	(junction
		(at 360.68 193.04)
		(diameter 0)
		(color 0 0 0 0)
	)
	(junction
		(at 386.08 68.58)
		(diameter 0)
		(color 0 0 0 0)
	)
	(junction
		(at 358.14 119.38)
		(diameter 0)
		(color 0 0 0 0)
	)
	(junction
		(at 146.05 165.1)
		(diameter 0)
		(color 0 0 0 0)
	)
	(junction
		(at 172.72 26.67)
		(diameter 0)
		(color 0 0 0 0)
	)
	(junction
		(at 302.26 193.04)
		(diameter 0)
		(color 0 0 0 0)
	)
	(junction
		(at 382.27 27.94)
		(diameter 0)
		(color 0 0 0 0)
	)
	(junction
		(at 189.23 187.96)
		(diameter 0)
		(color 0 0 0 0)
	)
	(junction
		(at 81.28 165.1)
		(diameter 0)
		(color 0 0 0 0)
	)
	(junction
		(at 71.12 165.1)
		(diameter 0)
		(color 0 0 0 0)
	)
	(junction
		(at 207.01 129.54)
		(diameter 0)
		(color 0 0 0 0)
	)
	(junction
		(at 173.99 54.61)
		(diameter 0)
		(color 0 0 0 0)
	)
	(junction
		(at 302.26 134.62)
		(diameter 0)
		(color 0 0 0 0)
	)
	(junction
		(at 50.8 191.77)
		(diameter 0)
		(color 0 0 0 0)
	)
	(junction
		(at 81.28 209.55)
		(diameter 0)
		(color 0 0 0 0)
	)
	(junction
		(at 58.42 191.77)
		(diameter 0)
		(color 0 0 0 0)
	)
	(junction
		(at 386.08 121.92)
		(diameter 0)
		(color 0 0 0 0)
	)
	(junction
		(at 50.8 118.11)
		(diameter 0)
		(color 0 0 0 0)
	)
	(junction
		(at 203.2 240.03)
		(diameter 0)
		(color 0 0 0 0)
	)
	(junction
		(at 50.8 165.1)
		(diameter 0)
		(color 0 0 0 0)
	)
	(junction
		(at 243.84 26.67)
		(diameter 0)
		(color 0 0 0 0)
	)
	(junction
		(at 302.26 142.24)
		(diameter 0)
		(color 0 0 0 0)
	)
	(junction
		(at 125.73 165.1)
		(diameter 0)
		(color 0 0 0 0)
	)
	(junction
		(at 382.27 30.48)
		(diameter 0)
		(color 0 0 0 0)
	)
	(junction
		(at 40.64 33.02)
		(diameter 0)
		(color 0 0 0 0)
	)
	(junction
		(at 213.36 274.32)
		(diameter 0)
		(color 0 0 0 0)
	)
	(junction
		(at 274.32 149.86)
		(diameter 0)
		(color 0 0 0 0)
	)
	(junction
		(at 58.42 144.78)
		(diameter 0)
		(color 0 0 0 0)
	)
	(junction
		(at 119.38 165.1)
		(diameter 0)
		(color 0 0 0 0)
	)
	(junction
		(at 73.66 193.04)
		(diameter 0)
		(color 0 0 0 0)
	)
	(junction
		(at 214.63 198.12)
		(diameter 0)
		(color 0 0 0 0)
	)
	(junction
		(at 144.78 52.07)
		(diameter 0)
		(color 0 0 0 0)
	)
	(junction
		(at 302.26 200.66)
		(diameter 0)
		(color 0 0 0 0)
	)
	(junction
		(at 30.48 123.19)
		(diameter 0)
		(color 0 0 0 0)
	)
	(junction
		(at 132.08 173.99)
		(diameter 0)
		(color 0 0 0 0)
	)
	(junction
		(at 299.72 134.62)
		(diameter 0)
		(color 0 0 0 0)
	)
	(junction
		(at 328.93 193.04)
		(diameter 0)
		(color 0 0 0 0)
	)
	(junction
		(at 365.76 193.04)
		(diameter 0)
		(color 0 0 0 0)
	)
	(junction
		(at 365.76 71.12)
		(diameter 0)
		(color 0 0 0 0)
	)
	(junction
		(at 246.38 49.53)
		(diameter 0)
		(color 0 0 0 0)
	)
	(junction
		(at 368.3 134.62)
		(diameter 0)
		(color 0 0 0 0)
	)
	(junction
		(at 336.55 193.04)
		(diameter 0)
		(color 0 0 0 0)
	)
	(junction
		(at 209.55 240.03)
		(diameter 0)
		(color 0 0 0 0)
	)
	(junction
		(at 355.6 193.04)
		(diameter 0)
		(color 0 0 0 0)
	)
	(junction
		(at 101.6 39.37)
		(diameter 0)
		(color 0 0 0 0)
	)
	(junction
		(at 182.88 41.91)
		(diameter 0)
		(color 0 0 0 0)
	)
	(junction
		(at 213.36 247.65)
		(diameter 0)
		(color 0 0 0 0)
	)
	(junction
		(at 151.13 54.61)
		(diameter 0)
		(color 0 0 0 0)
	)
	(junction
		(at 386.08 134.62)
		(diameter 0)
		(color 0 0 0 0)
	)
	(junction
		(at 106.68 59.69)
		(diameter 0)
		(color 0 0 0 0)
	)
	(junction
		(at 313.69 193.04)
		(diameter 0)
		(color 0 0 0 0)
	)
	(junction
		(at 233.68 113.03)
		(diameter 0)
		(color 0 0 0 0)
	)
	(junction
		(at 198.12 129.54)
		(diameter 0)
		(color 0 0 0 0)
	)
	(junction
		(at 233.68 203.2)
		(diameter 0)
		(color 0 0 0 0)
	)
	(junction
		(at 124.46 26.67)
		(diameter 0)
		(color 0 0 0 0)
	)
	(junction
		(at 269.24 251.46)
		(diameter 0)
		(color 0 0 0 0)
	)
	(junction
		(at 386.08 71.12)
		(diameter 0)
		(color 0 0 0 0)
	)
	(junction
		(at 189.23 129.54)
		(diameter 0)
		(color 0 0 0 0)
	)
	(junction
		(at 166.37 165.1)
		(diameter 0)
		(color 0 0 0 0)
	)
	(junction
		(at 374.65 143.51)
		(diameter 0)
		(color 0 0 0 0)
	)
	(junction
		(at 336.55 134.62)
		(diameter 0)
		(color 0 0 0 0)
	)
	(junction
		(at 109.22 165.1)
		(diameter 0)
		(color 0 0 0 0)
	)
	(junction
		(at 318.77 30.48)
		(diameter 0)
		(color 0 0 0 0)
	)
	(junction
		(at 86.36 59.69)
		(diameter 0)
		(color 0 0 0 0)
	)
	(junction
		(at 274.32 208.28)
		(diameter 0)
		(color 0 0 0 0)
	)
	(junction
		(at 313.69 134.62)
		(diameter 0)
		(color 0 0 0 0)
	)
	(junction
		(at 386.08 119.38)
		(diameter 0)
		(color 0 0 0 0)
	)
	(junction
		(at 119.38 173.99)
		(diameter 0)
		(color 0 0 0 0)
	)
	(junction
		(at 358.14 134.62)
		(diameter 0)
		(color 0 0 0 0)
	)
	(junction
		(at 35.56 71.12)
		(diameter 0)
		(color 0 0 0 0)
	)
	(junction
		(at 267.97 39.37)
		(diameter 0)
		(color 0 0 0 0)
	)
	(junction
		(at 330.2 30.48)
		(diameter 0)
		(color 0 0 0 0)
	)
	(junction
		(at 321.31 193.04)
		(diameter 0)
		(color 0 0 0 0)
	)
	(junction
		(at 321.31 134.62)
		(diameter 0)
		(color 0 0 0 0)
	)
	(junction
		(at 363.22 134.62)
		(diameter 0)
		(color 0 0 0 0)
	)
	(junction
		(at 38.1 118.11)
		(diameter 0)
		(color 0 0 0 0)
	)
	(junction
		(at 223.52 113.03)
		(diameter 0)
		(color 0 0 0 0)
	)
	(junction
		(at 101.6 59.69)
		(diameter 0)
		(color 0 0 0 0)
	)
	(junction
		(at 60.96 73.66)
		(diameter 0)
		(color 0 0 0 0)
	)
	(junction
		(at 233.68 144.78)
		(diameter 0)
		(color 0 0 0 0)
	)
	(junction
		(at 198.12 187.96)
		(diameter 0)
		(color 0 0 0 0)
	)
	(junction
		(at 328.93 134.62)
		(diameter 0)
		(color 0 0 0 0)
	)
	(junction
		(at 203.2 266.7)
		(diameter 0)
		(color 0 0 0 0)
	)
	(junction
		(at 60.96 62.23)
		(diameter 0)
		(color 0 0 0 0)
	)
	(junction
		(at 246.38 43.18)
		(diameter 0)
		(color 0 0 0 0)
	)
	(junction
		(at 73.66 146.05)
		(diameter 0)
		(color 0 0 0 0)
	)
	(junction
		(at 50.8 144.78)
		(diameter 0)
		(color 0 0 0 0)
	)
	(junction
		(at 173.99 41.91)
		(diameter 0)
		(color 0 0 0 0)
	)
	(junction
		(at 299.72 71.12)
		(diameter 0)
		(color 0 0 0 0)
	)
	(no_connect
		(at 67.31 57.15)
	)
	(no_connect
		(at 237.49 274.32)
	)
	(no_connect
		(at 273.05 137.16)
	)
	(no_connect
		(at 237.49 247.65)
	)
	(no_connect
		(at 273.05 195.58)
	)
	(no_connect
		(at 251.46 149.86)
	)
	(no_connect
		(at 251.46 208.28)
	)
	(wire
		(pts
			(xy 355.6 190.5) (xy 355.6 193.04)
		)
		(stroke
			(width 0)
			(type default)
		)
	)
	(wire
		(pts
			(xy 142.24 52.07) (xy 144.78 52.07)
		)
		(stroke
			(width 0)
			(type default)
		)
	)
	(wire
		(pts
			(xy 236.22 49.53) (xy 246.38 49.53)
		)
		(stroke
			(width 0)
			(type default)
		)
	)
	(wire
		(pts
			(xy 60.96 62.23) (xy 60.96 73.66)
		)
		(stroke
			(width 0)
			(type default)
		)
	)
	(wire
		(pts
			(xy 273.05 205.74) (xy 274.32 205.74)
		)
		(stroke
			(width 0)
			(type default)
		)
	)
	(wire
		(pts
			(xy 173.99 54.61) (xy 175.26 54.61)
		)
		(stroke
			(width 0)
			(type default)
		)
	)
	(wire
		(pts
			(xy 262.89 242.57) (xy 262.89 240.03)
		)
		(stroke
			(width 0)
			(type default)
		)
	)
	(wire
		(pts
			(xy 50.8 152.4) (xy 50.8 153.67)
		)
		(stroke
			(width 0)
			(type default)
		)
	)
	(wire
		(pts
			(xy 368.3 121.92) (xy 374.65 121.92)
		)
		(stroke
			(width 0)
			(type default)
		)
	)
	(polyline
		(pts
			(xy 83.82 69.85) (xy 83.82 40.64)
		)
		(stroke
			(width 0)
			(type default)
		)
	)
	(wire
		(pts
			(xy 214.63 247.65) (xy 213.36 247.65)
		)
		(stroke
			(width 0)
			(type default)
		)
	)
	(wire
		(pts
			(xy 71.12 191.77) (xy 58.42 191.77)
		)
		(stroke
			(width 0)
			(type default)
		)
	)
	(wire
		(pts
			(xy 336.55 134.62) (xy 336.55 143.51)
		)
		(stroke
			(width 0)
			(type default)
		)
	)
	(wire
		(pts
			(xy 73.66 152.4) (xy 73.66 153.67)
		)
		(stroke
			(width 0)
			(type default)
		)
	)
	(wire
		(pts
			(xy 43.18 73.66) (xy 43.18 81.28)
		)
		(stroke
			(width 0)
			(type default)
		)
	)
	(wire
		(pts
			(xy 368.3 134.62) (xy 370.84 134.62)
		)
		(stroke
			(width 0)
			(type default)
		)
	)
	(wire
		(pts
			(xy 273.05 198.12) (xy 299.72 198.12)
		)
		(stroke
			(width 0)
			(type default)
		)
	)
	(wire
		(pts
			(xy 223.52 111.76) (xy 223.52 113.03)
		)
		(stroke
			(width 0)
			(type default)
		)
	)
	(wire
		(pts
			(xy 233.68 212.09) (xy 233.68 213.36)
		)
		(stroke
			(width 0)
			(type default)
		)
	)
	(wire
		(pts
			(xy 365.76 77.47) (xy 365.76 78.74)
		)
		(stroke
			(width 0)
			(type default)
		)
	)
	(wire
		(pts
			(xy 242.57 195.58) (xy 251.46 195.58)
		)
		(stroke
			(width 0)
			(type default)
		)
	)
	(wire
		(pts
			(xy 270.51 39.37) (xy 267.97 39.37)
		)
		(stroke
			(width 0)
			(type default)
		)
	)
	(wire
		(pts
			(xy 73.66 146.05) (xy 73.66 147.32)
		)
		(stroke
			(width 0)
			(type default)
		)
	)
	(wire
		(pts
			(xy 313.69 193.04) (xy 313.69 201.93)
		)
		(stroke
			(width 0)
			(type default)
		)
	)
	(wire
		(pts
			(xy 336.55 193.04) (xy 336.55 201.93)
		)
		(stroke
			(width 0)
			(type default)
		)
	)
	(wire
		(pts
			(xy 214.63 207.01) (xy 214.63 198.12)
		)
		(stroke
			(width 0)
			(type default)
		)
	)
	(wire
		(pts
			(xy 242.57 205.74) (xy 251.46 205.74)
		)
		(stroke
			(width 0)
			(type default)
		)
	)
	(wire
		(pts
			(xy 35.56 71.12) (xy 35.56 74.93)
		)
		(stroke
			(width 0)
			(type default)
		)
	)
	(wire
		(pts
			(xy 273.05 147.32) (xy 274.32 147.32)
		)
		(stroke
			(width 0)
			(type default)
		)
	)
	(wire
		(pts
			(xy 207.01 147.32) (xy 207.01 154.94)
		)
		(stroke
			(width 0)
			(type default)
		)
	)
	(wire
		(pts
			(xy 50.8 129.54) (xy 58.42 129.54)
		)
		(stroke
			(width 0)
			(type default)
		)
	)
	(wire
		(pts
			(xy 223.52 200.66) (xy 251.46 200.66)
		)
		(stroke
			(width 0)
			(type default)
		)
	)
	(wire
		(pts
			(xy 58.42 190.5) (xy 58.42 191.77)
		)
		(stroke
			(width 0)
			(type default)
		)
	)
	(wire
		(pts
			(xy 207.01 129.54) (xy 207.01 142.24)
		)
		(stroke
			(width 0)
			(type default)
		)
	)
	(wire
		(pts
			(xy 162.56 265.43) (xy 162.56 270.51)
		)
		(stroke
			(width 0)
			(type default)
		)
	)
	(wire
		(pts
			(xy 363.22 134.62) (xy 358.14 134.62)
		)
		(stroke
			(width 0)
			(type default)
		)
	)
	(wire
		(pts
			(xy 321.31 193.04) (xy 321.31 201.93)
		)
		(stroke
			(width 0)
			(type default)
		)
	)
	(wire
		(pts
			(xy 36.83 41.91) (xy 36.83 46.99)
		)
		(stroke
			(width 0)
			(type default)
		)
	)
	(wire
		(pts
			(xy 214.63 139.7) (xy 251.46 139.7)
		)
		(stroke
			(width 0)
			(type default)
		)
	)
	(wire
		(pts
			(xy 242.57 147.32) (xy 242.57 148.59)
		)
		(stroke
			(width 0)
			(type default)
		)
	)
	(wire
		(pts
			(xy 40.64 33.02) (xy 40.64 34.29)
		)
		(stroke
			(width 0)
			(type default)
		)
	)
	(wire
		(pts
			(xy 38.1 118.11) (xy 38.1 119.38)
		)
		(stroke
			(width 0)
			(type default)
		)
	)
	(wire
		(pts
			(xy 386.08 68.58) (xy 386.08 67.31)
		)
		(stroke
			(width 0)
			(type default)
		)
	)
	(wire
		(pts
			(xy 166.37 162.56) (xy 166.37 165.1)
		)
		(stroke
			(width 0)
			(type default)
		)
	)
	(wire
		(pts
			(xy 189.23 147.32) (xy 189.23 154.94)
		)
		(stroke
			(width 0)
			(type default)
		)
	)
	(wire
		(pts
			(xy 321.31 207.01) (xy 321.31 213.36)
		)
		(stroke
			(width 0)
			(type default)
		)
	)
	(wire
		(pts
			(xy 269.24 251.46) (xy 269.24 262.89)
		)
		(stroke
			(width 0)
			(type default)
		)
	)
	(wire
		(pts
			(xy 81.28 209.55) (xy 81.28 217.17)
		)
		(stroke
			(width 0)
			(type default)
		)
	)
	(wire
		(pts
			(xy 213.36 236.22) (xy 214.63 236.22)
		)
		(stroke
			(width 0)
			(type default)
		)
	)
	(wire
		(pts
			(xy 262.89 274.32) (xy 262.89 279.4)
		)
		(stroke
			(width 0)
			(type default)
		)
	)
	(wire
		(pts
			(xy 209.55 245.11) (xy 214.63 245.11)
		)
		(stroke
			(width 0)
			(type default)
		)
	)
	(wire
		(pts
			(xy 119.38 165.1) (xy 125.73 165.1)
		)
		(stroke
			(width 0)
			(type default)
		)
	)
	(wire
		(pts
			(xy 189.23 187.96) (xy 189.23 200.66)
		)
		(stroke
			(width 0)
			(type default)
		)
	)
	(wire
		(pts
			(xy 246.38 50.8) (xy 246.38 49.53)
		)
		(stroke
			(width 0)
			(type default)
		)
	)
	(wire
		(pts
			(xy 209.55 240.03) (xy 214.63 240.03)
		)
		(stroke
			(width 0)
			(type default)
		)
	)
	(wire
		(pts
			(xy 60.96 33.02) (xy 60.96 39.37)
		)
		(stroke
			(width 0)
			(type default)
		)
	)
	(wire
		(pts
			(xy 34.29 71.12) (xy 35.56 71.12)
		)
		(stroke
			(width 0)
			(type default)
		)
	)
	(wire
		(pts
			(xy 182.88 41.91) (xy 182.88 44.45)
		)
		(stroke
			(width 0)
			(type default)
		)
	)
	(wire
		(pts
			(xy 106.68 67.31) (xy 106.68 68.58)
		)
		(stroke
			(width 0)
			(type default)
		)
	)
	(wire
		(pts
			(xy 363.22 134.62) (xy 368.3 134.62)
		)
		(stroke
			(width 0)
			(type default)
		)
	)
	(wire
		(pts
			(xy 58.42 144.78) (xy 50.8 144.78)
		)
		(stroke
			(width 0)
			(type default)
		)
	)
	(wire
		(pts
			(xy 256.54 261.62) (xy 256.54 271.78)
		)
		(stroke
			(width 0)
			(type default)
		)
	)
	(wire
		(pts
			(xy 106.68 59.69) (xy 127 59.69)
		)
		(stroke
			(width 0)
			(type default)
		)
	)
	(wire
		(pts
			(xy 346.71 30.48) (xy 355.6 30.48)
		)
		(stroke
			(width 0)
			(type default)
		)
	)
	(wire
		(pts
			(xy 233.68 148.59) (xy 233.68 144.78)
		)
		(stroke
			(width 0)
			(type default)
		)
	)
	(wire
		(pts
			(xy 262.89 247.65) (xy 262.89 250.19)
		)
		(stroke
			(width 0)
			(type default)
		)
	)
	(wire
		(pts
			(xy 241.3 242.57) (xy 241.3 246.38)
		)
		(stroke
			(width 0)
			(type default)
		)
	)
	(wire
		(pts
			(xy 60.96 80.01) (xy 60.96 81.28)
		)
		(stroke
			(width 0)
			(type default)
		)
	)
	(wire
		(pts
			(xy 63.5 217.17) (xy 81.28 217.17)
		)
		(stroke
			(width 0)
			(type default)
		)
	)
	(wire
		(pts
			(xy 151.13 57.15) (xy 151.13 54.61)
		)
		(stroke
			(width 0)
			(type default)
		)
	)
	(wire
		(pts
			(xy 274.32 213.36) (xy 274.32 208.28)
		)
		(stroke
			(width 0)
			(type default)
		)
	)
	(wire
		(pts
			(xy 321.31 134.62) (xy 321.31 143.51)
		)
		(stroke
			(width 0)
			(type default)
		)
	)
	(wire
		(pts
			(xy 63.5 173.99) (xy 63.5 172.72)
		)
		(stroke
			(width 0)
			(type default)
		)
	)
	(wire
		(pts
			(xy 162.56 247.65) (xy 162.56 248.92)
		)
		(stroke
			(width 0)
			(type default)
		)
	)
	(wire
		(pts
			(xy 355.6 78.74) (xy 355.6 73.66)
		)
		(stroke
			(width 0)
			(type default)
		)
	)
	(wire
		(pts
			(xy 346.71 119.38) (xy 346.71 116.84)
		)
		(stroke
			(width 0)
			(type default)
		)
	)
	(wire
		(pts
			(xy 237.49 245.11) (xy 254 245.11)
		)
		(stroke
			(width 0)
			(type default)
		)
	)
	(wire
		(pts
			(xy 328.93 193.04) (xy 336.55 193.04)
		)
		(stroke
			(width 0)
			(type default)
		)
	)
	(wire
		(pts
			(xy 363.22 143.51) (xy 363.22 140.97)
		)
		(stroke
			(width 0)
			(type default)
		)
	)
	(wire
		(pts
			(xy 30.48 123.19) (xy 30.48 120.65)
		)
		(stroke
			(width 0)
			(type default)
		)
	)
	(wire
		(pts
			(xy 207.01 205.74) (xy 207.01 213.36)
		)
		(stroke
			(width 0)
			(type default)
		)
	)
	(wire
		(pts
			(xy 81.28 62.23) (xy 81.28 63.5)
		)
		(stroke
			(width 0)
			(type default)
		)
	)
	(wire
		(pts
			(xy 267.97 52.07) (xy 267.97 57.15)
		)
		(stroke
			(width 0)
			(type default)
		)
	)
	(wire
		(pts
			(xy 63.5 129.54) (xy 63.5 130.81)
		)
		(stroke
			(width 0)
			(type default)
		)
	)
	(wire
		(pts
			(xy 156.21 165.1) (xy 156.21 166.37)
		)
		(stroke
			(width 0)
			(type default)
		)
	)
	(wire
		(pts
			(xy 151.13 41.91) (xy 151.13 44.45)
		)
		(stroke
			(width 0)
			(type default)
		)
	)
	(wire
		(pts
			(xy 336.55 193.04) (xy 344.17 193.04)
		)
		(stroke
			(width 0)
			(type default)
		)
	)
	(wire
		(pts
			(xy 213.36 236.22) (xy 213.36 233.68)
		)
		(stroke
			(width 0)
			(type default)
		)
	)
	(wire
		(pts
			(xy 214.63 148.59) (xy 214.63 139.7)
		)
		(stroke
			(width 0)
			(type default)
		)
	)
	(wire
		(pts
			(xy 166.37 165.1) (xy 168.91 165.1)
		)
		(stroke
			(width 0)
			(type default)
		)
	)
	(wire
		(pts
			(xy 143.51 151.13) (xy 143.51 165.1)
		)
		(stroke
			(width 0)
			(type default)
		)
	)
	(wire
		(pts
			(xy 73.66 127) (xy 73.66 146.05)
		)
		(stroke
			(width 0)
			(type default)
		)
	)
	(wire
		(pts
			(xy 318.77 30.48) (xy 318.77 31.75)
		)
		(stroke
			(width 0)
			(type default)
		)
	)
	(wire
		(pts
			(xy 242.57 147.32) (xy 251.46 147.32)
		)
		(stroke
			(width 0)
			(type default)
		)
	)
	(wire
		(pts
			(xy 38.1 124.46) (xy 38.1 125.73)
		)
		(stroke
			(width 0)
			(type default)
		)
	)
	(wire
		(pts
			(xy 125.73 151.13) (xy 132.08 151.13)
		)
		(stroke
			(width 0)
			(type default)
		)
	)
	(wire
		(pts
			(xy 58.42 143.51) (xy 58.42 144.78)
		)
		(stroke
			(width 0)
			(type default)
		)
	)
	(wire
		(pts
			(xy 242.57 181.61) (xy 242.57 195.58)
		)
		(stroke
			(width 0)
			(type default)
		)
	)
	(wire
		(pts
			(xy 214.63 269.24) (xy 213.36 269.24)
		)
		(stroke
			(width 0)
			(type default)
		)
	)
	(wire
		(pts
			(xy 321.31 148.59) (xy 321.31 154.94)
		)
		(stroke
			(width 0)
			(type default)
		)
	)
	(wire
		(pts
			(xy 214.63 132.08) (xy 233.68 132.08)
		)
		(stroke
			(width 0)
			(type default)
		)
	)
	(wire
		(pts
			(xy 81.28 165.1) (xy 109.22 165.1)
		)
		(stroke
			(width 0)
			(type default)
		)
	)
	(wire
		(pts
			(xy 214.63 132.08) (xy 214.63 133.35)
		)
		(stroke
			(width 0)
			(type default)
		)
	)
	(wire
		(pts
			(xy 226.06 49.53) (xy 226.06 50.8)
		)
		(stroke
			(width 0)
			(type default)
		)
	)
	(wire
		(pts
			(xy 80.01 62.23) (xy 81.28 62.23)
		)
		(stroke
			(width 0)
			(type default)
		)
	)
	(wire
		(pts
			(xy 386.08 121.92) (xy 386.08 134.62)
		)
		(stroke
			(width 0)
			(type default)
		)
	)
	(wire
		(pts
			(xy 313.69 207.01) (xy 313.69 213.36)
		)
		(stroke
			(width 0)
			(type default)
		)
	)
	(wire
		(pts
			(xy 382.27 30.48) (xy 384.81 30.48)
		)
		(stroke
			(width 0)
			(type default)
		)
	)
	(wire
		(pts
			(xy 233.68 153.67) (xy 233.68 154.94)
		)
		(stroke
			(width 0)
			(type default)
		)
	)
	(wire
		(pts
			(xy 198.12 129.54) (xy 207.01 129.54)
		)
		(stroke
			(width 0)
			(type default)
		)
	)
	(wire
		(pts
			(xy 237.49 266.7) (xy 262.89 266.7)
		)
		(stroke
			(width 0)
			(type default)
		)
	)
	(wire
		(pts
			(xy 233.68 207.01) (xy 233.68 203.2)
		)
		(stroke
			(width 0)
			(type default)
		)
	)
	(wire
		(pts
			(xy 313.69 193.04) (xy 321.31 193.04)
		)
		(stroke
			(width 0)
			(type default)
		)
	)
	(wire
		(pts
			(xy 144.78 52.07) (xy 175.26 52.07)
		)
		(stroke
			(width 0)
			(type default)
		)
	)
	(wire
		(pts
			(xy 198.12 200.66) (xy 198.12 187.96)
		)
		(stroke
			(width 0)
			(type default)
		)
	)
	(wire
		(pts
			(xy 101.6 59.69) (xy 106.68 59.69)
		)
		(stroke
			(width 0)
			(type default)
		)
	)
	(wire
		(pts
			(xy 86.36 34.29) (xy 86.36 59.69)
		)
		(stroke
			(width 0)
			(type default)
		)
	)
	(wire
		(pts
			(xy 330.2 35.56) (xy 330.2 38.1)
		)
		(stroke
			(width 0)
			(type default)
		)
	)
	(wire
		(pts
			(xy 71.12 129.54) (xy 71.12 118.11)
		)
		(stroke
			(width 0)
			(type default)
		)
	)
	(wire
		(pts
			(xy 156.21 165.1) (xy 166.37 165.1)
		)
		(stroke
			(width 0)
			(type default)
		)
	)
	(wire
		(pts
			(xy 313.69 134.62) (xy 313.69 143.51)
		)
		(stroke
			(width 0)
			(type default)
		)
	)
	(wire
		(pts
			(xy 140.97 165.1) (xy 143.51 165.1)
		)
		(stroke
			(width 0)
			(type default)
		)
	)
	(wire
		(pts
			(xy 299.72 71.12) (xy 299.72 72.39)
		)
		(stroke
			(width 0)
			(type default)
		)
	)
	(wire
		(pts
			(xy 81.28 118.11) (xy 81.28 165.1)
		)
		(stroke
			(width 0)
			(type default)
		)
	)
	(wire
		(pts
			(xy 330.2 35.56) (xy 331.47 35.56)
		)
		(stroke
			(width 0)
			(type default)
		)
	)
	(wire
		(pts
			(xy 302.26 143.51) (xy 302.26 142.24)
		)
		(stroke
			(width 0)
			(type default)
		)
	)
	(wire
		(pts
			(xy 223.52 212.09) (xy 223.52 213.36)
		)
		(stroke
			(width 0)
			(type default)
		)
	)
	(wire
		(pts
			(xy 173.99 41.91) (xy 173.99 49.53)
		)
		(stroke
			(width 0)
			(type default)
		)
	)
	(wire
		(pts
			(xy 370.84 30.48) (xy 382.27 30.48)
		)
		(stroke
			(width 0)
			(type default)
		)
	)
	(wire
		(pts
			(xy 40.64 44.45) (xy 40.64 45.72)
		)
		(stroke
			(width 0)
			(type default)
		)
	)
	(wire
		(pts
			(xy 60.96 74.93) (xy 60.96 73.66)
		)
		(stroke
			(width 0)
			(type default)
		)
	)
	(wire
		(pts
			(xy 156.21 177.8) (xy 156.21 181.61)
		)
		(stroke
			(width 0)
			(type default)
		)
	)
	(wire
		(pts
			(xy 214.63 274.32) (xy 213.36 274.32)
		)
		(stroke
			(width 0)
			(type default)
		)
	)
	(polyline
		(pts
			(xy 180.34 219.71) (xy 180.34 95.25)
		)
		(stroke
			(width 0)
			(type default)
		)
	)
	(wire
		(pts
			(xy 358.14 119.38) (xy 358.14 116.84)
		)
		(stroke
			(width 0)
			(type default)
		)
	)
	(wire
		(pts
			(xy 143.51 64.77) (xy 144.78 64.77)
		)
		(stroke
			(width 0)
			(type default)
		)
	)
	(wire
		(pts
			(xy 365.76 30.48) (xy 355.6 30.48)
		)
		(stroke
			(width 0)
			(type default)
		)
	)
	(wire
		(pts
			(xy 151.13 54.61) (xy 173.99 54.61)
		)
		(stroke
			(width 0)
			(type default)
		)
	)
	(wire
		(pts
			(xy 43.18 33.02) (xy 60.96 33.02)
		)
		(stroke
			(width 0)
			(type default)
		)
	)
	(wire
		(pts
			(xy 86.36 59.69) (xy 91.44 59.69)
		)
		(stroke
			(width 0)
			(type default)
		)
	)
	(wire
		(pts
			(xy 166.37 172.72) (xy 166.37 181.61)
		)
		(stroke
			(width 0)
			(type default)
		)
	)
	(wire
		(pts
			(xy 132.08 180.34) (xy 132.08 181.61)
		)
		(stroke
			(width 0)
			(type default)
		)
	)
	(wire
		(pts
			(xy 58.42 191.77) (xy 50.8 191.77)
		)
		(stroke
			(width 0)
			(type default)
		)
	)
	(wire
		(pts
			(xy 50.8 144.78) (xy 50.8 147.32)
		)
		(stroke
			(width 0)
			(type default)
		)
	)
	(wire
		(pts
			(xy 302.26 134.62) (xy 313.69 134.62)
		)
		(stroke
			(width 0)
			(type default)
		)
	)
	(wire
		(pts
			(xy 261.62 49.53) (xy 246.38 49.53)
		)
		(stroke
			(width 0)
			(type default)
		)
	)
	(wire
		(pts
			(xy 50.8 176.53) (xy 58.42 176.53)
		)
		(stroke
			(width 0)
			(type default)
		)
	)
	(wire
		(pts
			(xy 119.38 165.1) (xy 119.38 166.37)
		)
		(stroke
			(width 0)
			(type default)
		)
	)
	(polyline
		(pts
			(xy 297.18 219.71) (xy 297.18 284.48)
		)
		(stroke
			(width 0)
			(type default)
		)
	)
	(wire
		(pts
			(xy 209.55 245.11) (xy 209.55 240.03)
		)
		(stroke
			(width 0)
			(type default)
		)
	)
	(wire
		(pts
			(xy 189.23 205.74) (xy 189.23 213.36)
		)
		(stroke
			(width 0)
			(type default)
		)
	)
	(wire
		(pts
			(xy 289.56 187.96) (xy 288.29 187.96)
		)
		(stroke
			(width 0)
			(type default)
		)
	)
	(wire
		(pts
			(xy 273.05 132.08) (xy 289.56 132.08)
		)
		(stroke
			(width 0)
			(type default)
		)
	)
	(wire
		(pts
			(xy 332.74 73.66) (xy 339.09 73.66)
		)
		(stroke
			(width 0)
			(type default)
		)
	)
	(wire
		(pts
			(xy 302.26 140.97) (xy 302.26 142.24)
		)
		(stroke
			(width 0)
			(type default)
		)
	)
	(wire
		(pts
			(xy 354.33 71.12) (xy 365.76 71.12)
		)
		(stroke
			(width 0)
			(type default)
		)
	)
	(wire
		(pts
			(xy 213.36 242.57) (xy 213.36 247.65)
		)
		(stroke
			(width 0)
			(type default)
		)
	)
	(wire
		(pts
			(xy 142.24 59.69) (xy 143.51 59.69)
		)
		(stroke
			(width 0)
			(type default)
		)
	)
	(wire
		(pts
			(xy 203.2 266.7) (xy 203.2 262.89)
		)
		(stroke
			(width 0)
			(type default)
		)
	)
	(wire
		(pts
			(xy 393.7 119.38) (xy 393.7 116.84)
		)
		(stroke
			(width 0)
			(type default)
		)
	)
	(wire
		(pts
			(xy 71.12 184.15) (xy 71.12 191.77)
		)
		(stroke
			(width 0)
			(type default)
		)
	)
	(wire
		(pts
			(xy 273.05 187.96) (xy 283.21 187.96)
		)
		(stroke
			(width 0)
			(type default)
		)
	)
	(wire
		(pts
			(xy 71.12 118.11) (xy 81.28 118.11)
		)
		(stroke
			(width 0)
			(type default)
		)
	)
	(wire
		(pts
			(xy 233.68 113.03) (xy 242.57 113.03)
		)
		(stroke
			(width 0)
			(type default)
		)
	)
	(wire
		(pts
			(xy 318.77 30.48) (xy 330.2 30.48)
		)
		(stroke
			(width 0)
			(type default)
		)
	)
	(wire
		(pts
			(xy 360.68 193.04) (xy 365.76 193.04)
		)
		(stroke
			(width 0)
			(type default)
		)
	)
	(wire
		(pts
			(xy 63.5 176.53) (xy 71.12 176.53)
		)
		(stroke
			(width 0)
			(type default)
		)
	)
	(wire
		(pts
			(xy 336.55 134.62) (xy 344.17 134.62)
		)
		(stroke
			(width 0)
			(type default)
		)
	)
	(wire
		(pts
			(xy 273.05 129.54) (xy 283.21 129.54)
		)
		(stroke
			(width 0)
			(type default)
		)
	)
	(wire
		(pts
			(xy 365.76 71.12) (xy 365.76 72.39)
		)
		(stroke
			(width 0)
			(type default)
		)
	)
	(wire
		(pts
			(xy 302.26 193.04) (xy 313.69 193.04)
		)
		(stroke
			(width 0)
			(type default)
		)
	)
	(wire
		(pts
			(xy 260.35 245.11) (xy 260.35 234.95)
		)
		(stroke
			(width 0)
			(type default)
		)
	)
	(wire
		(pts
			(xy 124.46 27.94) (xy 124.46 26.67)
		)
		(stroke
			(width 0)
			(type default)
		)
	)
	(wire
		(pts
			(xy 237.49 262.89) (xy 269.24 262.89)
		)
		(stroke
			(width 0)
			(type default)
		)
	)
	(wire
		(pts
			(xy 289.56 190.5) (xy 289.56 187.96)
		)
		(stroke
			(width 0)
			(type default)
		)
	)
	(wire
		(pts
			(xy 151.13 41.91) (xy 173.99 41.91)
		)
		(stroke
			(width 0)
			(type default)
		)
	)
	(wire
		(pts
			(xy 50.8 184.15) (xy 52.07 184.15)
		)
		(stroke
			(width 0)
			(type default)
		)
	)
	(wire
		(pts
			(xy 274.32 154.94) (xy 274.32 149.86)
		)
		(stroke
			(width 0)
			(type default)
		)
	)
	(wire
		(pts
			(xy 73.66 193.04) (xy 73.66 194.31)
		)
		(stroke
			(width 0)
			(type default)
		)
	)
	(wire
		(pts
			(xy 223.52 153.67) (xy 223.52 154.94)
		)
		(stroke
			(width 0)
			(type default)
		)
	)
	(wire
		(pts
			(xy 125.73 165.1) (xy 128.27 165.1)
		)
		(stroke
			(width 0)
			(type default)
		)
	)
	(wire
		(pts
			(xy 299.72 69.85) (xy 299.72 71.12)
		)
		(stroke
			(width 0)
			(type default)
		)
	)
	(wire
		(pts
			(xy 328.93 134.62) (xy 328.93 143.51)
		)
		(stroke
			(width 0)
			(type default)
		)
	)
	(wire
		(pts
			(xy 349.25 134.62) (xy 358.14 134.62)
		)
		(stroke
			(width 0)
			(type default)
		)
	)
	(wire
		(pts
			(xy 182.88 60.96) (xy 182.88 59.69)
		)
		(stroke
			(width 0)
			(type default)
		)
	)
	(wire
		(pts
			(xy 86.36 26.67) (xy 86.36 29.21)
		)
		(stroke
			(width 0)
			(type default)
		)
	)
	(wire
		(pts
			(xy 198.12 147.32) (xy 198.12 154.94)
		)
		(stroke
			(width 0)
			(type default)
		)
	)
	(wire
		(pts
			(xy 223.52 113.03) (xy 223.52 114.3)
		)
		(stroke
			(width 0)
			(type default)
		)
	)
	(wire
		(pts
			(xy 318.77 27.94) (xy 318.77 30.48)
		)
		(stroke
			(width 0)
			(type default)
		)
	)
	(wire
		(pts
			(xy 269.24 251.46) (xy 274.32 251.46)
		)
		(stroke
			(width 0)
			(type default)
		)
	)
	(wire
		(pts
			(xy 198.12 142.24) (xy 198.12 129.54)
		)
		(stroke
			(width 0)
			(type default)
		)
	)
	(wire
		(pts
			(xy 254 76.2) (xy 248.92 76.2)
		)
		(stroke
			(width 0)
			(type default)
		)
	)
	(wire
		(pts
			(xy 101.6 52.07) (xy 127 52.07)
		)
		(stroke
			(width 0)
			(type default)
		)
	)
	(wire
		(pts
			(xy 50.8 191.77) (xy 50.8 194.31)
		)
		(stroke
			(width 0)
			(type default)
		)
	)
	(wire
		(pts
			(xy 151.13 49.53) (xy 151.13 54.61)
		)
		(stroke
			(width 0)
			(type default)
		)
	)
	(wire
		(pts
			(xy 146.05 165.1) (xy 156.21 165.1)
		)
		(stroke
			(width 0)
			(type default)
		)
	)
	(wire
		(pts
			(xy 226.06 55.88) (xy 226.06 57.15)
		)
		(stroke
			(width 0)
			(type default)
		)
	)
	(wire
		(pts
			(xy 382.27 27.94) (xy 382.27 30.48)
		)
		(stroke
			(width 0)
			(type default)
		)
	)
	(polyline
		(pts
			(xy 62.23 69.85) (xy 83.82 69.85)
		)
		(stroke
			(width 0)
			(type default)
		)
	)
	(wire
		(pts
			(xy 358.14 134.62) (xy 358.14 135.89)
		)
		(stroke
			(width 0)
			(type default)
		)
	)
	(wire
		(pts
			(xy 43.18 33.02) (xy 43.18 34.29)
		)
		(stroke
			(width 0)
			(type default)
		)
	)
	(wire
		(pts
			(xy 203.2 238.76) (xy 203.2 240.03)
		)
		(stroke
			(width 0)
			(type default)
		)
	)
	(wire
		(pts
			(xy 172.72 27.94) (xy 172.72 26.67)
		)
		(stroke
			(width 0)
			(type default)
		)
	)
	(wire
		(pts
			(xy 109.22 171.45) (xy 109.22 173.99)
		)
		(stroke
			(width 0)
			(type default)
		)
	)
	(wire
		(pts
			(xy 153.67 264.16) (xy 153.67 262.89)
		)
		(stroke
			(width 0)
			(type default)
		)
	)
	(wire
		(pts
			(xy 299.72 198.12) (xy 299.72 193.04)
		)
		(stroke
			(width 0)
			(type default)
		)
	)
	(wire
		(pts
			(xy 137.16 151.13) (xy 143.51 151.13)
		)
		(stroke
			(width 0)
			(type default)
		)
	)
	(polyline
		(pts
			(xy 12.7 95.25) (xy 407.67 95.25)
		)
		(stroke
			(width 0)
			(type default)
		)
	)
	(wire
		(pts
			(xy 143.51 262.89) (xy 153.67 262.89)
		)
		(stroke
			(width 0)
			(type default)
		)
	)
	(wire
		(pts
			(xy 274.32 208.28) (xy 274.32 205.74)
		)
		(stroke
			(width 0)
			(type default)
		)
	)
	(wire
		(pts
			(xy 63.5 129.54) (xy 71.12 129.54)
		)
		(stroke
			(width 0)
			(type default)
		)
	)
	(wire
		(pts
			(xy 63.5 193.04) (xy 73.66 193.04)
		)
		(stroke
			(width 0)
			(type default)
		)
	)
	(wire
		(pts
			(xy 374.65 143.51) (xy 363.22 143.51)
		)
		(stroke
			(width 0)
			(type default)
		)
	)
	(wire
		(pts
			(xy 40.64 33.02) (xy 43.18 33.02)
		)
		(stroke
			(width 0)
			(type default)
		)
	)
	(wire
		(pts
			(xy 360.68 193.04) (xy 360.68 201.93)
		)
		(stroke
			(width 0)
			(type default)
		)
	)
	(wire
		(pts
			(xy 365.76 190.5) (xy 365.76 193.04)
		)
		(stroke
			(width 0)
			(type default)
		)
	)
	(wire
		(pts
			(xy 203.2 266.7) (xy 214.63 266.7)
		)
		(stroke
			(width 0)
			(type default)
		)
	)
	(wire
		(pts
			(xy 114.3 39.37) (xy 144.78 39.37)
		)
		(stroke
			(width 0)
			(type default)
		)
	)
	(wire
		(pts
			(xy 71.12 137.16) (xy 71.12 144.78)
		)
		(stroke
			(width 0)
			(type default)
		)
	)
	(polyline
		(pts
			(xy 62.23 40.64) (xy 62.23 69.85)
		)
		(stroke
			(width 0)
			(type default)
		)
	)
	(wire
		(pts
			(xy 246.38 26.67) (xy 246.38 31.75)
		)
		(stroke
			(width 0)
			(type default)
		)
	)
	(wire
		(pts
			(xy 146.05 165.1) (xy 146.05 166.37)
		)
		(stroke
			(width 0)
			(type default)
		)
	)
	(wire
		(pts
			(xy 242.57 153.67) (xy 242.57 154.94)
		)
		(stroke
			(width 0)
			(type default)
		)
	)
	(wire
		(pts
			(xy 223.52 105.41) (xy 223.52 106.68)
		)
		(stroke
			(width 0)
			(type default)
		)
	)
	(polyline
		(pts
			(xy 135.89 284.48) (xy 135.89 219.71)
		)
		(stroke
			(width 0)
			(type default)
		)
	)
	(wire
		(pts
			(xy 71.12 144.78) (xy 58.42 144.78)
		)
		(stroke
			(width 0)
			(type default)
		)
	)
	(wire
		(pts
			(xy 273.05 139.7) (xy 299.72 139.7)
		)
		(stroke
			(width 0)
			(type default)
		)
	)
	(wire
		(pts
			(xy 223.52 119.38) (xy 223.52 120.65)
		)
		(stroke
			(width 0)
			(type default)
		)
	)
	(wire
		(pts
			(xy 213.36 274.32) (xy 213.36 279.4)
		)
		(stroke
			(width 0)
			(type default)
		)
	)
	(wire
		(pts
			(xy 156.21 162.56) (xy 156.21 165.1)
		)
		(stroke
			(width 0)
			(type default)
		)
	)
	(wire
		(pts
			(xy 242.57 137.16) (xy 251.46 137.16)
		)
		(stroke
			(width 0)
			(type default)
		)
	)
	(wire
		(pts
			(xy 328.93 193.04) (xy 328.93 201.93)
		)
		(stroke
			(width 0)
			(type default)
		)
	)
	(wire
		(pts
			(xy 143.51 59.69) (xy 143.51 64.77)
		)
		(stroke
			(width 0)
			(type default)
		)
	)
	(wire
		(pts
			(xy 203.2 260.35) (xy 203.2 262.89)
		)
		(stroke
			(width 0)
			(type default)
		)
	)
	(wire
		(pts
			(xy 243.84 41.91) (xy 243.84 43.18)
		)
		(stroke
			(width 0)
			(type default)
		)
	)
	(wire
		(pts
			(xy 330.2 30.48) (xy 331.47 30.48)
		)
		(stroke
			(width 0)
			(type default)
		)
	)
	(wire
		(pts
			(xy 189.23 187.96) (xy 198.12 187.96)
		)
		(stroke
			(width 0)
			(type default)
		)
	)
	(wire
		(pts
			(xy 355.6 30.48) (xy 355.6 31.75)
		)
		(stroke
			(width 0)
			(type default)
		)
	)
	(wire
		(pts
			(xy 198.12 205.74) (xy 198.12 213.36)
		)
		(stroke
			(width 0)
			(type default)
		)
	)
	(wire
		(pts
			(xy 50.8 118.11) (xy 54.61 118.11)
		)
		(stroke
			(width 0)
			(type default)
		)
	)
	(wire
		(pts
			(xy 223.52 142.24) (xy 223.52 148.59)
		)
		(stroke
			(width 0)
			(type default)
		)
	)
	(wire
		(pts
			(xy 328.93 148.59) (xy 328.93 154.94)
		)
		(stroke
			(width 0)
			(type default)
		)
	)
	(wire
		(pts
			(xy 71.12 165.1) (xy 81.28 165.1)
		)
		(stroke
			(width 0)
			(type default)
		)
	)
	(wire
		(pts
			(xy 226.06 49.53) (xy 236.22 49.53)
		)
		(stroke
			(width 0)
			(type default)
		)
	)
	(wire
		(pts
			(xy 132.08 172.72) (xy 132.08 173.99)
		)
		(stroke
			(width 0)
			(type default)
		)
	)
	(wire
		(pts
			(xy 383.54 27.94) (xy 382.27 27.94)
		)
		(stroke
			(width 0)
			(type default)
		)
	)
	(wire
		(pts
			(xy 214.63 196.85) (xy 214.63 198.12)
		)
		(stroke
			(width 0)
			(type default)
		)
	)
	(wire
		(pts
			(xy 30.48 123.19) (xy 29.21 123.19)
		)
		(stroke
			(width 0)
			(type default)
		)
	)
	(wire
		(pts
			(xy 223.52 200.66) (xy 223.52 207.01)
		)
		(stroke
			(width 0)
			(type default)
		)
	)
	(wire
		(pts
			(xy 151.13 69.85) (xy 151.13 67.31)
		)
		(stroke
			(width 0)
			(type default)
		)
	)
	(wire
		(pts
			(xy 237.49 242.57) (xy 241.3 242.57)
		)
		(stroke
			(width 0)
			(type default)
		)
	)
	(wire
		(pts
			(xy 173.99 74.93) (xy 173.99 78.74)
		)
		(stroke
			(width 0)
			(type default)
		)
	)
	(wire
		(pts
			(xy 119.38 173.99) (xy 132.08 173.99)
		)
		(stroke
			(width 0)
			(type default)
		)
	)
	(wire
		(pts
			(xy 241.3 269.24) (xy 241.3 273.05)
		)
		(stroke
			(width 0)
			(type default)
		)
	)
	(wire
		(pts
			(xy 374.65 142.24) (xy 374.65 143.51)
		)
		(stroke
			(width 0)
			(type default)
		)
	)
	(wire
		(pts
			(xy 63.5 209.55) (xy 81.28 209.55)
		)
		(stroke
			(width 0)
			(type default)
		)
	)
	(wire
		(pts
			(xy 173.99 54.61) (xy 173.99 69.85)
		)
		(stroke
			(width 0)
			(type default)
		)
	)
	(wire
		(pts
			(xy 73.66 173.99) (xy 73.66 193.04)
		)
		(stroke
			(width 0)
			(type default)
		)
	)
	(wire
		(pts
			(xy 273.05 134.62) (xy 293.37 134.62)
		)
		(stroke
			(width 0)
			(type default)
		)
	)
	(wire
		(pts
			(xy 106.68 59.69) (xy 106.68 62.23)
		)
		(stroke
			(width 0)
			(type default)
		)
	)
	(wire
		(pts
			(xy 119.38 171.45) (xy 119.38 173.99)
		)
		(stroke
			(width 0)
			(type default)
		)
	)
	(wire
		(pts
			(xy 363.22 135.89) (xy 363.22 134.62)
		)
		(stroke
			(width 0)
			(type default)
		)
	)
	(wire
		(pts
			(xy 236.22 50.8) (xy 236.22 49.53)
		)
		(stroke
			(width 0)
			(type default)
		)
	)
	(polyline
		(pts
			(xy 135.89 219.71) (xy 180.34 219.71)
		)
		(stroke
			(width 0)
			(type default)
		)
	)
	(wire
		(pts
			(xy 198.12 187.96) (xy 207.01 187.96)
		)
		(stroke
			(width 0)
			(type default)
		)
	)
	(polyline
		(pts
			(xy 289.56 12.7) (xy 289.56 93.98)
		)
		(stroke
			(width 0)
			(type default)
		)
	)
	(wire
		(pts
			(xy 170.18 26.67) (xy 172.72 26.67)
		)
		(stroke
			(width 0)
			(type default)
		)
	)
	(wire
		(pts
			(xy 121.92 26.67) (xy 124.46 26.67)
		)
		(stroke
			(width 0)
			(type default)
		)
	)
	(wire
		(pts
			(xy 207.01 187.96) (xy 207.01 200.66)
		)
		(stroke
			(width 0)
			(type default)
		)
	)
	(wire
		(pts
			(xy 378.46 71.12) (xy 386.08 71.12)
		)
		(stroke
			(width 0)
			(type default)
		)
	)
	(wire
		(pts
			(xy 50.8 144.78) (xy 50.8 137.16)
		)
		(stroke
			(width 0)
			(type default)
		)
	)
	(wire
		(pts
			(xy 267.97 39.37) (xy 267.97 41.91)
		)
		(stroke
			(width 0)
			(type default)
		)
	)
	(wire
		(pts
			(xy 242.57 212.09) (xy 242.57 213.36)
		)
		(stroke
			(width 0)
			(type default)
		)
	)
	(wire
		(pts
			(xy 299.72 71.12) (xy 339.09 71.12)
		)
		(stroke
			(width 0)
			(type default)
		)
	)
	(wire
		(pts
			(xy 289.56 129.54) (xy 289.56 132.08)
		)
		(stroke
			(width 0)
			(type default)
		)
	)
	(wire
		(pts
			(xy 273.05 193.04) (xy 293.37 193.04)
		)
		(stroke
			(width 0)
			(type default)
		)
	)
	(wire
		(pts
			(xy 44.45 217.17) (xy 58.42 217.17)
		)
		(stroke
			(width 0)
			(type default)
		)
	)
	(wire
		(pts
			(xy 67.31 165.1) (xy 71.12 165.1)
		)
		(stroke
			(width 0)
			(type default)
		)
	)
	(wire
		(pts
			(xy 233.68 119.38) (xy 233.68 120.65)
		)
		(stroke
			(width 0)
			(type default)
		)
	)
	(wire
		(pts
			(xy 29.21 118.11) (xy 38.1 118.11)
		)
		(stroke
			(width 0)
			(type default)
		)
	)
	(wire
		(pts
			(xy 60.96 62.23) (xy 67.31 62.23)
		)
		(stroke
			(width 0)
			(type default)
		)
	)
	(wire
		(pts
			(xy 60.96 39.37) (xy 60.96 62.23)
		)
		(stroke
			(width 0)
			(type default)
		)
	)
	(wire
		(pts
			(xy 246.38 55.88) (xy 246.38 57.15)
		)
		(stroke
			(width 0)
			(type default)
		)
	)
	(wire
		(pts
			(xy 262.89 266.7) (xy 262.89 269.24)
		)
		(stroke
			(width 0)
			(type default)
		)
	)
	(wire
		(pts
			(xy 321.31 193.04) (xy 328.93 193.04)
		)
		(stroke
			(width 0)
			(type default)
		)
	)
	(wire
		(pts
			(xy 214.63 191.77) (xy 214.63 190.5)
		)
		(stroke
			(width 0)
			(type default)
		)
	)
	(wire
		(pts
			(xy 213.36 269.24) (xy 213.36 274.32)
		)
		(stroke
			(width 0)
			(type default)
		)
	)
	(wire
		(pts
			(xy 125.73 151.13) (xy 125.73 165.1)
		)
		(stroke
			(width 0)
			(type default)
		)
	)
	(wire
		(pts
			(xy 172.72 181.61) (xy 172.72 180.34)
		)
		(stroke
			(width 0)
			(type default)
		)
	)
	(wire
		(pts
			(xy 200.66 240.03) (xy 203.2 240.03)
		)
		(stroke
			(width 0)
			(type default)
		)
	)
	(wire
		(pts
			(xy 156.21 78.74) (xy 162.56 78.74)
		)
		(stroke
			(width 0)
			(type default)
		)
	)
	(wire
		(pts
			(xy 156.21 171.45) (xy 156.21 172.72)
		)
		(stroke
			(width 0)
			(type default)
		)
	)
	(wire
		(pts
			(xy 346.71 33.02) (xy 347.98 33.02)
		)
		(stroke
			(width 0)
			(type default)
		)
	)
	(wire
		(pts
			(xy 35.56 80.01) (xy 35.56 81.28)
		)
		(stroke
			(width 0)
			(type default)
		)
	)
	(wire
		(pts
			(xy 189.23 187.96) (xy 189.23 186.69)
		)
		(stroke
			(width 0)
			(type default)
		)
	)
	(polyline
		(pts
			(xy 62.23 40.64) (xy 83.82 40.64)
		)
		(stroke
			(width 0)
			(type default)
		)
	)
	(wire
		(pts
			(xy 30.48 120.65) (xy 29.21 120.65)
		)
		(stroke
			(width 0)
			(type default)
		)
	)
	(wire
		(pts
			(xy 313.69 134.62) (xy 321.31 134.62)
		)
		(stroke
			(width 0)
			(type default)
		)
	)
	(wire
		(pts
			(xy 260.35 245.11) (xy 259.08 245.11)
		)
		(stroke
			(width 0)
			(type default)
		)
	)
	(wire
		(pts
			(xy 237.49 240.03) (xy 262.89 240.03)
		)
		(stroke
			(width 0)
			(type default)
		)
	)
	(wire
		(pts
			(xy 71.12 184.15) (xy 69.85 184.15)
		)
		(stroke
			(width 0)
			(type default)
		)
	)
	(wire
		(pts
			(xy 63.5 146.05) (xy 73.66 146.05)
		)
		(stroke
			(width 0)
			(type default)
		)
	)
	(wire
		(pts
			(xy 382.27 36.83) (xy 382.27 38.1)
		)
		(stroke
			(width 0)
			(type default)
		)
	)
	(wire
		(pts
			(xy 382.27 27.94) (xy 382.27 26.67)
		)
		(stroke
			(width 0)
			(type default)
		)
	)
	(wire
		(pts
			(xy 214.63 138.43) (xy 214.63 139.7)
		)
		(stroke
			(width 0)
			(type default)
		)
	)
	(wire
		(pts
			(xy 50.8 191.77) (xy 50.8 184.15)
		)
		(stroke
			(width 0)
			(type default)
		)
	)
	(wire
		(pts
			(xy 189.23 129.54) (xy 198.12 129.54)
		)
		(stroke
			(width 0)
			(type default)
		)
	)
	(wire
		(pts
			(xy 243.84 26.67) (xy 243.84 31.75)
		)
		(stroke
			(width 0)
			(type default)
		)
	)
	(wire
		(pts
			(xy 233.68 144.78) (xy 251.46 144.78)
		)
		(stroke
			(width 0)
			(type default)
		)
	)
	(wire
		(pts
			(xy 207.01 187.96) (xy 251.46 187.96)
		)
		(stroke
			(width 0)
			(type default)
		)
	)
	(wire
		(pts
			(xy 246.38 43.18) (xy 246.38 49.53)
		)
		(stroke
			(width 0)
			(type default)
		)
	)
	(wire
		(pts
			(xy 274.32 251.46) (xy 274.32 250.19)
		)
		(stroke
			(width 0)
			(type default)
		)
	)
	(wire
		(pts
			(xy 172.72 33.02) (xy 172.72 34.29)
		)
		(stroke
			(width 0)
			(type default)
		)
	)
	(wire
		(pts
			(xy 207.01 129.54) (xy 251.46 129.54)
		)
		(stroke
			(width 0)
			(type default)
		)
	)
	(polyline
		(pts
			(xy 180.34 219.71) (xy 297.18 219.71)
		)
		(stroke
			(width 0)
			(type default)
		)
	)
	(wire
		(pts
			(xy 63.5 127) (xy 73.66 127)
		)
		(stroke
			(width 0)
			(type default)
		)
	)
	(wire
		(pts
			(xy 328.93 134.62) (xy 336.55 134.62)
		)
		(stroke
			(width 0)
			(type default)
		)
	)
	(wire
		(pts
			(xy 175.26 49.53) (xy 173.99 49.53)
		)
		(stroke
			(width 0)
			(type default)
		)
	)
	(wire
		(pts
			(xy 80.01 59.69) (xy 86.36 59.69)
		)
		(stroke
			(width 0)
			(type default)
		)
	)
	(wire
		(pts
			(xy 43.18 62.23) (xy 60.96 62.23)
		)
		(stroke
			(width 0)
			(type default)
		)
	)
	(wire
		(pts
			(xy 63.5 143.51) (xy 63.5 146.05)
		)
		(stroke
			(width 0)
			(type default)
		)
	)
	(wire
		(pts
			(xy 50.8 199.39) (xy 50.8 200.66)
		)
		(stroke
			(width 0)
			(type default)
		)
	)
	(wire
		(pts
			(xy 96.52 59.69) (xy 101.6 59.69)
		)
		(stroke
			(width 0)
			(type default)
		)
	)
	(wire
		(pts
			(xy 383.54 134.62) (xy 386.08 134.62)
		)
		(stroke
			(width 0)
			(type default)
		)
	)
	(wire
		(pts
			(xy 386.08 116.84) (xy 386.08 119.38)
		)
		(stroke
			(width 0)
			(type default)
		)
	)
	(wire
		(pts
			(xy 386.08 71.12) (xy 397.51 71.12)
		)
		(stroke
			(width 0)
			(type default)
		)
	)
	(wire
		(pts
			(xy 386.08 134.62) (xy 388.62 134.62)
		)
		(stroke
			(width 0)
			(type default)
		)
	)
	(wire
		(pts
			(xy 302.26 148.59) (xy 302.26 154.94)
		)
		(stroke
			(width 0)
			(type default)
		)
	)
	(wire
		(pts
			(xy 134.62 69.85) (xy 134.62 68.58)
		)
		(stroke
			(width 0)
			(type default)
		)
	)
	(wire
		(pts
			(xy 214.63 190.5) (xy 233.68 190.5)
		)
		(stroke
			(width 0)
			(type default)
		)
	)
	(wire
		(pts
			(xy 58.42 129.54) (xy 58.42 130.81)
		)
		(stroke
			(width 0)
			(type default)
		)
	)
	(wire
		(pts
			(xy 199.39 49.53) (xy 205.74 49.53)
		)
		(stroke
			(width 0)
			(type default)
		)
	)
	(wire
		(pts
			(xy 124.46 33.02) (xy 124.46 34.29)
		)
		(stroke
			(width 0)
			(type default)
		)
	)
	(wire
		(pts
			(xy 146.05 171.45) (xy 146.05 173.99)
		)
		(stroke
			(width 0)
			(type default)
		)
	)
	(wire
		(pts
			(xy 43.18 45.72) (xy 43.18 44.45)
		)
		(stroke
			(width 0)
			(type default)
		)
	)
	(wire
		(pts
			(xy 189.23 142.24) (xy 189.23 129.54)
		)
		(stroke
			(width 0)
			(type default)
		)
	)
	(wire
		(pts
			(xy 382.27 31.75) (xy 382.27 30.48)
		)
		(stroke
			(width 0)
			(type default)
		)
	)
	(wire
		(pts
			(xy 101.6 39.37) (xy 109.22 39.37)
		)
		(stroke
			(width 0)
			(type default)
		)
	)
	(wire
		(pts
			(xy 236.22 55.88) (xy 236.22 57.15)
		)
		(stroke
			(width 0)
			(type default)
		)
	)
	(wire
		(pts
			(xy 299.72 134.62) (xy 302.26 134.62)
		)
		(stroke
			(width 0)
			(type default)
		)
	)
	(wire
		(pts
			(xy 360.68 207.01) (xy 360.68 213.36)
		)
		(stroke
			(width 0)
			(type default)
		)
	)
	(wire
		(pts
			(xy 214.63 153.67) (xy 214.63 154.94)
		)
		(stroke
			(width 0)
			(type default)
		)
	)
	(wire
		(pts
			(xy 60.96 73.66) (xy 90.17 73.66)
		)
		(stroke
			(width 0)
			(type default)
		)
	)
	(wire
		(pts
			(xy 386.08 119.38) (xy 386.08 121.92)
		)
		(stroke
			(width 0)
			(type default)
		)
	)
	(wire
		(pts
			(xy 299.72 139.7) (xy 299.72 134.62)
		)
		(stroke
			(width 0)
			(type default)
		)
	)
	(wire
		(pts
			(xy 86.36 26.67) (xy 82.55 26.67)
		)
		(stroke
			(width 0)
			(type default)
		)
	)
	(wire
		(pts
			(xy 162.56 241.3) (xy 162.56 242.57)
		)
		(stroke
			(width 0)
			(type default)
		)
	)
	(wire
		(pts
			(xy 302.26 207.01) (xy 302.26 213.36)
		)
		(stroke
			(width 0)
			(type default)
		)
	)
	(wire
		(pts
			(xy 43.18 46.99) (xy 43.18 45.72)
		)
		(stroke
			(width 0)
			(type default)
		)
	)
	(wire
		(pts
			(xy 73.66 199.39) (xy 73.66 200.66)
		)
		(stroke
			(width 0)
			(type default)
		)
	)
	(polyline
		(pts
			(xy 289.56 50.8) (xy 407.67 50.8)
		)
		(stroke
			(width 0)
			(type default)
		)
	)
	(wire
		(pts
			(xy 246.38 43.18) (xy 246.38 41.91)
		)
		(stroke
			(width 0)
			(type default)
		)
	)
	(wire
		(pts
			(xy 346.71 119.38) (xy 358.14 119.38)
		)
		(stroke
			(width 0)
			(type default)
		)
	)
	(wire
		(pts
			(xy 214.63 212.09) (xy 214.63 213.36)
		)
		(stroke
			(width 0)
			(type default)
		)
	)
	(wire
		(pts
			(xy 330.2 30.48) (xy 330.2 33.02)
		)
		(stroke
			(width 0)
			(type default)
		)
	)
	(wire
		(pts
			(xy 267.97 36.83) (xy 267.97 39.37)
		)
		(stroke
			(width 0)
			(type default)
		)
	)
	(wire
		(pts
			(xy 44.45 209.55) (xy 58.42 209.55)
		)
		(stroke
			(width 0)
			(type default)
		)
	)
	(wire
		(pts
			(xy 302.26 199.39) (xy 302.26 200.66)
		)
		(stroke
			(width 0)
			(type default)
		)
	)
	(wire
		(pts
			(xy 299.72 193.04) (xy 302.26 193.04)
		)
		(stroke
			(width 0)
			(type default)
		)
	)
	(wire
		(pts
			(xy 242.57 113.03) (xy 242.57 137.16)
		)
		(stroke
			(width 0)
			(type default)
		)
	)
	(wire
		(pts
			(xy 153.67 269.24) (xy 153.67 270.51)
		)
		(stroke
			(width 0)
			(type default)
		)
	)
	(wire
		(pts
			(xy 50.8 118.11) (xy 50.8 129.54)
		)
		(stroke
			(width 0)
			(type default)
		)
	)
	(wire
		(pts
			(xy 143.51 165.1) (xy 146.05 165.1)
		)
		(stroke
			(width 0)
			(type default)
		)
	)
	(wire
		(pts
			(xy 43.18 63.5) (xy 43.18 62.23)
		)
		(stroke
			(width 0)
			(type default)
		)
	)
	(wire
		(pts
			(xy 397.51 71.12) (xy 397.51 67.31)
		)
		(stroke
			(width 0)
			(type default)
		)
	)
	(wire
		(pts
			(xy 274.32 149.86) (xy 274.32 147.32)
		)
		(stroke
			(width 0)
			(type default)
		)
	)
	(wire
		(pts
			(xy 173.99 41.91) (xy 182.88 41.91)
		)
		(stroke
			(width 0)
			(type default)
		)
	)
	(wire
		(pts
			(xy 233.68 113.03) (xy 233.68 114.3)
		)
		(stroke
			(width 0)
			(type default)
		)
	)
	(wire
		(pts
			(xy 167.64 78.74) (xy 173.99 78.74)
		)
		(stroke
			(width 0)
			(type default)
		)
	)
	(wire
		(pts
			(xy 242.57 205.74) (xy 242.57 207.01)
		)
		(stroke
			(width 0)
			(type default)
		)
	)
	(wire
		(pts
			(xy 203.2 232.41) (xy 203.2 233.68)
		)
		(stroke
			(width 0)
			(type default)
		)
	)
	(wire
		(pts
			(xy 273.05 190.5) (xy 289.56 190.5)
		)
		(stroke
			(width 0)
			(type default)
		)
	)
	(wire
		(pts
			(xy 153.67 262.89) (xy 156.21 262.89)
		)
		(stroke
			(width 0)
			(type default)
		)
	)
	(wire
		(pts
			(xy 273.05 142.24) (xy 302.26 142.24)
		)
		(stroke
			(width 0)
			(type default)
		)
	)
	(wire
		(pts
			(xy 299.72 77.47) (xy 299.72 78.74)
		)
		(stroke
			(width 0)
			(type default)
		)
	)
	(wire
		(pts
			(xy 237.49 236.22) (xy 269.24 236.22)
		)
		(stroke
			(width 0)
			(type default)
		)
	)
	(wire
		(pts
			(xy 71.12 176.53) (xy 71.12 165.1)
		)
		(stroke
			(width 0)
			(type default)
		)
	)
	(wire
		(pts
			(xy 190.5 49.53) (xy 194.31 49.53)
		)
		(stroke
			(width 0)
			(type default)
		)
	)
	(wire
		(pts
			(xy 302.26 193.04) (xy 302.26 194.31)
		)
		(stroke
			(width 0)
			(type default)
		)
	)
	(wire
		(pts
			(xy 298.45 134.62) (xy 299.72 134.62)
		)
		(stroke
			(width 0)
			(type default)
		)
	)
	(wire
		(pts
			(xy 144.78 39.37) (xy 144.78 52.07)
		)
		(stroke
			(width 0)
			(type default)
		)
	)
	(wire
		(pts
			(xy 50.8 137.16) (xy 52.07 137.16)
		)
		(stroke
			(width 0)
			(type default)
		)
	)
	(wire
		(pts
			(xy 302.26 134.62) (xy 302.26 135.89)
		)
		(stroke
			(width 0)
			(type default)
		)
	)
	(wire
		(pts
			(xy 273.05 149.86) (xy 274.32 149.86)
		)
		(stroke
			(width 0)
			(type default)
		)
	)
	(wire
		(pts
			(xy 241.3 278.13) (xy 241.3 279.4)
		)
		(stroke
			(width 0)
			(type default)
		)
	)
	(wire
		(pts
			(xy 347.98 33.02) (xy 347.98 38.1)
		)
		(stroke
			(width 0)
			(type default)
		)
	)
	(wire
		(pts
			(xy 58.42 176.53) (xy 58.42 177.8)
		)
		(stroke
			(width 0)
			(type default)
		)
	)
	(wire
		(pts
			(xy 30.48 125.73) (xy 30.48 123.19)
		)
		(stroke
			(width 0)
			(type default)
		)
	)
	(wire
		(pts
			(xy 328.93 207.01) (xy 328.93 213.36)
		)
		(stroke
			(width 0)
			(type default)
		)
	)
	(wire
		(pts
			(xy 322.58 73.66) (xy 327.66 73.66)
		)
		(stroke
			(width 0)
			(type default)
		)
	)
	(wire
		(pts
			(xy 302.26 201.93) (xy 302.26 200.66)
		)
		(stroke
			(width 0)
			(type default)
		)
	)
	(wire
		(pts
			(xy 243.84 76.2) (xy 237.49 76.2)
		)
		(stroke
			(width 0)
			(type default)
		)
	)
	(wire
		(pts
			(xy 233.68 190.5) (xy 233.68 203.2)
		)
		(stroke
			(width 0)
			(type default)
		)
	)
	(wire
		(pts
			(xy 101.6 73.66) (xy 101.6 59.69)
		)
		(stroke
			(width 0)
			(type default)
		)
	)
	(wire
		(pts
			(xy 223.52 142.24) (xy 251.46 142.24)
		)
		(stroke
			(width 0)
			(type default)
		)
	)
	(wire
		(pts
			(xy 386.08 119.38) (xy 393.7 119.38)
		)
		(stroke
			(width 0)
			(type default)
		)
	)
	(wire
		(pts
			(xy 273.05 208.28) (xy 274.32 208.28)
		)
		(stroke
			(width 0)
			(type default)
		)
	)
	(wire
		(pts
			(xy 48.26 165.1) (xy 50.8 165.1)
		)
		(stroke
			(width 0)
			(type default)
		)
	)
	(wire
		(pts
			(xy 95.25 73.66) (xy 101.6 73.66)
		)
		(stroke
			(width 0)
			(type default)
		)
	)
	(wire
		(pts
			(xy 256.54 271.78) (xy 251.46 271.78)
		)
		(stroke
			(width 0)
			(type default)
		)
	)
	(wire
		(pts
			(xy 318.77 36.83) (xy 318.77 38.1)
		)
		(stroke
			(width 0)
			(type default)
		)
	)
	(wire
		(pts
			(xy 132.08 173.99) (xy 146.05 173.99)
		)
		(stroke
			(width 0)
			(type default)
		)
	)
	(wire
		(pts
			(xy 246.38 43.18) (xy 243.84 43.18)
		)
		(stroke
			(width 0)
			(type default)
		)
	)
	(wire
		(pts
			(xy 36.83 33.02) (xy 36.83 36.83)
		)
		(stroke
			(width 0)
			(type default)
		)
	)
	(wire
		(pts
			(xy 134.62 26.67) (xy 134.62 43.18)
		)
		(stroke
			(width 0)
			(type default)
		)
	)
	(wire
		(pts
			(xy 246.38 26.67) (xy 243.84 26.67)
		)
		(stroke
			(width 0)
			(type default)
		)
	)
	(wire
		(pts
			(xy 321.31 134.62) (xy 328.93 134.62)
		)
		(stroke
			(width 0)
			(type default)
		)
	)
	(wire
		(pts
			(xy 40.64 45.72) (xy 43.18 45.72)
		)
		(stroke
			(width 0)
			(type default)
		)
	)
	(wire
		(pts
			(xy 365.76 71.12) (xy 373.38 71.12)
		)
		(stroke
			(width 0)
			(type default)
		)
	)
	(wire
		(pts
			(xy 336.55 148.59) (xy 336.55 154.94)
		)
		(stroke
			(width 0)
			(type default)
		)
	)
	(wire
		(pts
			(xy 223.52 113.03) (xy 233.68 113.03)
		)
		(stroke
			(width 0)
			(type default)
		)
	)
	(polyline
		(pts
			(xy 180.34 170.18) (xy 407.67 170.18)
		)
		(stroke
			(width 0)
			(type default)
		)
	)
	(wire
		(pts
			(xy 189.23 129.54) (xy 189.23 128.27)
		)
		(stroke
			(width 0)
			(type default)
		)
	)
	(wire
		(pts
			(xy 386.08 68.58) (xy 386.08 71.12)
		)
		(stroke
			(width 0)
			(type default)
		)
	)
	(wire
		(pts
			(xy 387.35 68.58) (xy 386.08 68.58)
		)
		(stroke
			(width 0)
			(type default)
		)
	)
	(wire
		(pts
			(xy 63.5 173.99) (xy 73.66 173.99)
		)
		(stroke
			(width 0)
			(type default)
		)
	)
	(wire
		(pts
			(xy 374.65 143.51) (xy 374.65 144.78)
		)
		(stroke
			(width 0)
			(type default)
		)
	)
	(wire
		(pts
			(xy 237.49 269.24) (xy 241.3 269.24)
		)
		(stroke
			(width 0)
			(type default)
		)
	)
	(wire
		(pts
			(xy 63.5 127) (xy 63.5 125.73)
		)
		(stroke
			(width 0)
			(type default)
		)
	)
	(wire
		(pts
			(xy 132.08 175.26) (xy 132.08 173.99)
		)
		(stroke
			(width 0)
			(type default)
		)
	)
	(wire
		(pts
			(xy 109.22 173.99) (xy 119.38 173.99)
		)
		(stroke
			(width 0)
			(type default)
		)
	)
	(wire
		(pts
			(xy 50.8 165.1) (xy 54.61 165.1)
		)
		(stroke
			(width 0)
			(type default)
		)
	)
	(wire
		(pts
			(xy 203.2 240.03) (xy 209.55 240.03)
		)
		(stroke
			(width 0)
			(type default)
		)
	)
	(wire
		(pts
			(xy 336.55 207.01) (xy 336.55 213.36)
		)
		(stroke
			(width 0)
			(type default)
		)
	)
	(wire
		(pts
			(xy 237.49 271.78) (xy 246.38 271.78)
		)
		(stroke
			(width 0)
			(type default)
		)
	)
	(wire
		(pts
			(xy 71.12 137.16) (xy 69.85 137.16)
		)
		(stroke
			(width 0)
			(type default)
		)
	)
	(wire
		(pts
			(xy 124.46 26.67) (xy 134.62 26.67)
		)
		(stroke
			(width 0)
			(type default)
		)
	)
	(wire
		(pts
			(xy 172.72 26.67) (xy 182.88 26.67)
		)
		(stroke
			(width 0)
			(type default)
		)
	)
	(wire
		(pts
			(xy 365.76 152.4) (xy 368.3 152.4)
		)
		(stroke
			(width 0)
			(type default)
		)
	)
	(wire
		(pts
			(xy 241.3 26.67) (xy 243.84 26.67)
		)
		(stroke
			(width 0)
			(type default)
		)
	)
	(wire
		(pts
			(xy 60.96 39.37) (xy 101.6 39.37)
		)
		(stroke
			(width 0)
			(type default)
		)
	)
	(wire
		(pts
			(xy 269.24 236.22) (xy 269.24 251.46)
		)
		(stroke
			(width 0)
			(type default)
		)
	)
	(wire
		(pts
			(xy 358.14 140.97) (xy 358.14 142.24)
		)
		(stroke
			(width 0)
			(type default)
		)
	)
	(wire
		(pts
			(xy 240.03 181.61) (xy 242.57 181.61)
		)
		(stroke
			(width 0)
			(type default)
		)
	)
	(wire
		(pts
			(xy 50.8 165.1) (xy 50.8 176.53)
		)
		(stroke
			(width 0)
			(type default)
		)
	)
	(wire
		(pts
			(xy 355.6 36.83) (xy 355.6 38.1)
		)
		(stroke
			(width 0)
			(type default)
		)
	)
	(wire
		(pts
			(xy 313.69 148.59) (xy 313.69 154.94)
		)
		(stroke
			(width 0)
			(type default)
		)
	)
	(wire
		(pts
			(xy 374.65 154.94) (xy 374.65 156.21)
		)
		(stroke
			(width 0)
			(type default)
		)
	)
	(wire
		(pts
			(xy 331.47 33.02) (xy 330.2 33.02)
		)
		(stroke
			(width 0)
			(type default)
		)
	)
	(wire
		(pts
			(xy 213.36 247.65) (xy 213.36 250.19)
		)
		(stroke
			(width 0)
			(type default)
		)
	)
	(wire
		(pts
			(xy 273.05 200.66) (xy 302.26 200.66)
		)
		(stroke
			(width 0)
			(type default)
		)
	)
	(wire
		(pts
			(xy 203.2 271.78) (xy 214.63 271.78)
		)
		(stroke
			(width 0)
			(type default)
		)
	)
	(wire
		(pts
			(xy 355.6 73.66) (xy 354.33 73.66)
		)
		(stroke
			(width 0)
			(type default)
		)
	)
	(wire
		(pts
			(xy 166.37 165.1) (xy 166.37 167.64)
		)
		(stroke
			(width 0)
			(type default)
		)
	)
	(wire
		(pts
			(xy 232.41 181.61) (xy 234.95 181.61)
		)
		(stroke
			(width 0)
			(type default)
		)
	)
	(wire
		(pts
			(xy 358.14 134.62) (xy 358.14 119.38)
		)
		(stroke
			(width 0)
			(type default)
		)
	)
	(wire
		(pts
			(xy 63.5 176.53) (xy 63.5 177.8)
		)
		(stroke
			(width 0)
			(type default)
		)
	)
	(wire
		(pts
			(xy 241.3 251.46) (xy 241.3 252.73)
		)
		(stroke
			(width 0)
			(type default)
		)
	)
	(wire
		(pts
			(xy 288.29 129.54) (xy 289.56 129.54)
		)
		(stroke
			(width 0)
			(type default)
		)
	)
	(wire
		(pts
			(xy 63.5 190.5) (xy 63.5 193.04)
		)
		(stroke
			(width 0)
			(type default)
		)
	)
	(wire
		(pts
			(xy 233.68 132.08) (xy 233.68 144.78)
		)
		(stroke
			(width 0)
			(type default)
		)
	)
	(wire
		(pts
			(xy 162.56 254) (xy 162.56 255.27)
		)
		(stroke
			(width 0)
			(type default)
		)
	)
	(wire
		(pts
			(xy 81.28 165.1) (xy 81.28 209.55)
		)
		(stroke
			(width 0)
			(type default)
		)
	)
	(wire
		(pts
			(xy 203.2 271.78) (xy 203.2 266.7)
		)
		(stroke
			(width 0)
			(type default)
		)
	)
	(wire
		(pts
			(xy 386.08 71.12) (xy 386.08 72.39)
		)
		(stroke
			(width 0)
			(type default)
		)
	)
	(wire
		(pts
			(xy 298.45 193.04) (xy 299.72 193.04)
		)
		(stroke
			(width 0)
			(type default)
		)
	)
	(wire
		(pts
			(xy 203.2 262.89) (xy 214.63 262.89)
		)
		(stroke
			(width 0)
			(type default)
		)
	)
	(wire
		(pts
			(xy 355.6 193.04) (xy 360.68 193.04)
		)
		(stroke
			(width 0)
			(type default)
		)
	)
	(wire
		(pts
			(xy 35.56 71.12) (xy 36.83 71.12)
		)
		(stroke
			(width 0)
			(type default)
		)
	)
	(wire
		(pts
			(xy 213.36 242.57) (xy 214.63 242.57)
		)
		(stroke
			(width 0)
			(type default)
		)
	)
	(wire
		(pts
			(xy 182.88 26.67) (xy 182.88 41.91)
		)
		(stroke
			(width 0)
			(type default)
		)
	)
	(wire
		(pts
			(xy 365.76 193.04) (xy 367.03 193.04)
		)
		(stroke
			(width 0)
			(type default)
		)
	)
	(wire
		(pts
			(xy 214.63 198.12) (xy 251.46 198.12)
		)
		(stroke
			(width 0)
			(type default)
		)
	)
	(wire
		(pts
			(xy 386.08 77.47) (xy 386.08 78.74)
		)
		(stroke
			(width 0)
			(type default)
		)
	)
	(wire
		(pts
			(xy 109.22 165.1) (xy 119.38 165.1)
		)
		(stroke
			(width 0)
			(type default)
		)
	)
	(wire
		(pts
			(xy 379.73 121.92) (xy 386.08 121.92)
		)
		(stroke
			(width 0)
			(type default)
		)
	)
	(wire
		(pts
			(xy 101.6 39.37) (xy 101.6 52.07)
		)
		(stroke
			(width 0)
			(type default)
		)
	)
	(wire
		(pts
			(xy 109.22 165.1) (xy 109.22 166.37)
		)
		(stroke
			(width 0)
			(type default)
		)
	)
	(wire
		(pts
			(xy 349.25 193.04) (xy 355.6 193.04)
		)
		(stroke
			(width 0)
			(type default)
		)
	)
	(wire
		(pts
			(xy 368.3 121.92) (xy 368.3 134.62)
		)
		(stroke
			(width 0)
			(type default)
		)
	)
	(wire
		(pts
			(xy 67.31 118.11) (xy 71.12 118.11)
		)
		(stroke
			(width 0)
			(type default)
		)
	)
	(wire
		(pts
			(xy 233.68 203.2) (xy 251.46 203.2)
		)
		(stroke
			(width 0)
			(type default)
		)
	)
	(wire
		(pts
			(xy 38.1 118.11) (xy 50.8 118.11)
		)
		(stroke
			(width 0)
			(type default)
		)
	)
	(wire
		(pts
			(xy 40.64 33.02) (xy 36.83 33.02)
		)
		(stroke
			(width 0)
			(type default)
		)
	)
	(text "5V @12A\n"
		(exclude_from_sim no)
		(at 304.8 132.08 0)
		(effects
			(font
				(size 1.27 1.27)
			)
			(justify left bottom)
		)
	)
	(text "Sets UVLO to 8.4V"
		(exclude_from_sim no)
		(at 212.852 113.792 0)
		(effects
			(font
				(size 1.27 1.27)
			)
		)
	)
	(text "V_{OUT} = 0.6*(R_{FB_H}+R_{FB_L})/R_{FB_L}\n"
		(exclude_from_sim no)
		(at 300.99 166.37 0)
		(effects
			(font
				(size 1.27 1.27)
			)
			(justify left bottom)
		)
	)
	(text "3V3 STANDBY LDO"
		(exclude_from_sim no)
		(at 290.83 17.78 0)
		(effects
			(font
				(size 2.5 2.5)
				(bold yes)
			)
			(justify left bottom)
		)
	)
	(text "V_{OUT} = 0.6*(R_{FB_H}+R_{FB_L})/R_{FB_L}\n"
		(exclude_from_sim no)
		(at 300.99 224.79 0)
		(effects
			(font
				(size 1.27 1.27)
			)
			(justify left bottom)
		)
	)
	(text "3.3V\n@150mA"
		(exclude_from_sim no)
		(at 397.51 29.21 0)
		(effects
			(font
				(size 1.27 1.27)
			)
			(justify left bottom)
		)
	)
	(text "MODIFIED CIRCUIT \nFROM TI's SCEA048B AN"
		(exclude_from_sim no)
		(at 120.65 92.71 0)
		(effects
			(font
				(size 1.273 1.273)
			)
			(justify left bottom)
		)
	)
	(text "1V8 LDO"
		(exclude_from_sim no)
		(at 290.83 57.15 0)
		(effects
			(font
				(size 2.5 2.5)
				(bold yes)
			)
			(justify left bottom)
		)
	)
	(text "R_{FB_H} = (R_{FB_L}(V_{OUT}-0.6))/0.6\n"
		(exclude_from_sim no)
		(at 300.99 222.25 0)
		(effects
			(font
				(size 1.27 1.27)
			)
			(justify left bottom)
		)
	)
	(text "SHORT PRESS - POWER UP\nLONG PRESS  - POWER DOWN"
		(exclude_from_sim no)
		(at 36.83 31.115 0)
		(effects
			(font
				(size 1 1)
			)
			(justify left bottom)
		)
	)
	(text "5V DCDC"
		(exclude_from_sim no)
		(at 182.88 101.6 0)
		(effects
			(font
				(size 2.5 2.5)
				(bold yes)
			)
			(justify left bottom)
		)
	)
	(text "NOTE:\nSW1 STARTUP CRTL\n1-2 AUTO \n3-2 MANUAL"
		(exclude_from_sim no)
		(at 63.5 50.8 0)
		(effects
			(font
				(size 1.27 1.27)
			)
			(justify left bottom)
		)
	)
	(text "V_{OUT} = 0.6*(73k2+10k)/10k = 4.992[V]"
		(exclude_from_sim no)
		(at 300.99 168.91 0)
		(effects
			(font
				(size 1.27 1.27)
			)
			(justify left bottom)
		)
	)
	(text "Alternative parts: \n* LM73100 (set R283, R284 to 0R)\n"
		(exclude_from_sim no)
		(at 260.604 225.044 0)
		(effects
			(font
				(size 1.27 1.27)
			)
			(justify left bottom)
		)
	)
	(text "V_{OUT} = 0.6*(45k3+10k)/10k = 3.318[V]"
		(exclude_from_sim no)
		(at 300.99 227.33 0)
		(effects
			(font
				(size 1.27 1.27)
			)
			(justify left bottom)
		)
	)
	(text "High power module\nindicator"
		(exclude_from_sim no)
		(at 169.418 252.476 0)
		(effects
			(font
				(size 1.27 1.27)
			)
			(justify left bottom)
		)
	)
	(text "POWER BUTTON"
		(exclude_from_sim no)
		(at 36.83 27.305 0)
		(effects
			(font
				(size 1.5 1.5)
				(thickness 0.4)
				(bold yes)
			)
			(justify left bottom)
		)
	)
	(text "POWER-UP AND RESET CIRCUITRY"
		(exclude_from_sim no)
		(at 13.97 19.05 0)
		(effects
			(font
				(size 2.5 2.5)
				(bold yes)
			)
			(justify left bottom)
		)
	)
	(text "3V3 @12A"
		(exclude_from_sim no)
		(at 304.8 190.5 0)
		(effects
			(font
				(size 1.27 1.27)
			)
			(justify left bottom)
		)
	)
	(text "9 - 20 V "
		(exclude_from_sim no)
		(at 38.735 117.475 0)
		(effects
			(font
				(size 1.27 1.27)
			)
			(justify left bottom)
		)
	)
	(text "R_{FB_H} = (R_{FB_L}(V_{OUT}-0.6))/0.6\n"
		(exclude_from_sim no)
		(at 300.99 163.83 0)
		(effects
			(font
				(size 1.27 1.27)
			)
			(justify left bottom)
		)
	)
	(text "3V3 DCDC"
		(exclude_from_sim no)
		(at 182.88 176.53 0)
		(effects
			(font
				(size 2.5 2.5)
				(bold yes)
			)
			(justify left bottom)
		)
	)
	(text "PD CONTROLLER HAS \nIDEAL DIODE BUILT-IN"
		(exclude_from_sim no)
		(at 50.8 224.79 0)
		(effects
			(font
				(size 1.27 1.27)
			)
			(justify left bottom)
		)
	)
	(text "INPUT SELECTOR AND SOFT START"
		(exclude_from_sim no)
		(at 13.97 102.235 0)
		(effects
			(font
				(size 2.5 2.5)
				(bold yes)
			)
			(justify left bottom)
		)
	)
	(text "1.8V\n@200mA"
		(exclude_from_sim no)
		(at 398.145 71.12 0)
		(effects
			(font
				(size 1.27 1.27)
			)
			(justify left bottom)
		)
	)
	(text "SoM supply selector"
		(exclude_from_sim no)
		(at 182.88 225.806 0)
		(effects
			(font
				(size 2.5 2.5)
				(bold yes)
			)
			(justify left bottom)
		)
	)
	(text "RESET BUTTON"
		(exclude_from_sim no)
		(at 238.125 22.86 0)
		(effects
			(font
				(size 1.5 1.5)
				(thickness 0.4)
				(bold yes)
			)
			(justify left bottom)
		)
	)
	(label "3V3_LDO"
		(at 355.6 30.48 180)
		(effects
			(font
				(size 1.27 1.27)
			)
			(justify right bottom)
		)
	)
	(label "3V3_VDRV"
		(at 250.19 205.74 180)
		(effects
			(font
				(size 1.27 1.27)
			)
			(justify right bottom)
		)
	)
	(label "5V_SW"
		(at 274.32 134.62 0)
		(effects
			(font
				(size 1.27 1.27)
			)
			(justify left bottom)
		)
	)
	(label "5V_BOOT"
		(at 274.32 129.54 0)
		(effects
			(font
				(size 1.27 1.27)
			)
			(justify left bottom)
		)
	)
	(label "5V_GATE"
		(at 364.49 143.51 0)
		(effects
			(font
				(size 1.27 1.27)
			)
			(justify left bottom)
		)
	)
	(label "3V3_SW"
		(at 274.32 193.04 0)
		(effects
			(font
				(size 1.27 1.27)
			)
			(justify left bottom)
		)
	)
	(label "3V3_BOOT"
		(at 274.32 187.96 0)
		(effects
			(font
				(size 1.27 1.27)
			)
			(justify left bottom)
		)
	)
	(label "3V3_MODE1"
		(at 250.19 198.12 180)
		(effects
			(font
				(size 1.27 1.27)
			)
			(justify right bottom)
		)
	)
	(label "5V_EN"
		(at 250.19 137.16 180)
		(effects
			(font
				(size 1.27 1.27)
			)
			(justify right bottom)
		)
	)
	(label "3V3_FB"
		(at 274.32 200.66 0)
		(effects
			(font
				(size 1.27 1.27)
			)
			(justify left bottom)
		)
	)
	(label "3V3_VDD"
		(at 250.19 203.2 180)
		(effects
			(font
				(size 1.27 1.27)
			)
			(justify right bottom)
		)
	)
	(label "5V_OUT"
		(at 304.8 134.62 0)
		(effects
			(font
				(size 1.27 1.27)
			)
			(justify left bottom)
		)
	)
	(label "1V8_LDO"
		(at 364.49 71.12 180)
		(effects
			(font
				(size 1.27 1.27)
			)
			(justify right bottom)
		)
	)
	(label "5V_VDRV"
		(at 250.19 147.32 180)
		(effects
			(font
				(size 1.27 1.27)
			)
			(justify right bottom)
		)
	)
	(label "3V3_PHASE"
		(at 274.32 190.5 0)
		(effects
			(font
				(size 1.27 1.27)
			)
			(justify left bottom)
		)
	)
	(label "5V_PHASE"
		(at 274.32 132.08 0)
		(effects
			(font
				(size 1.27 1.27)
			)
			(justify left bottom)
		)
	)
	(label "3V3_MODE2"
		(at 250.19 200.66 180)
		(effects
			(font
				(size 1.27 1.27)
			)
			(justify right bottom)
		)
	)
	(label "3V3_OUT"
		(at 304.8 193.04 0)
		(effects
			(font
				(size 1.27 1.27)
			)
			(justify left bottom)
		)
	)
	(label "5V_FB"
		(at 274.32 142.24 0)
		(effects
			(font
				(size 1.27 1.27)
			)
			(justify left bottom)
		)
	)
	(label "5V_MODE1"
		(at 250.19 139.7 180)
		(effects
			(font
				(size 1.27 1.27)
			)
			(justify right bottom)
		)
	)
	(label "PG_{HP}"
		(at 242.57 245.11 0)
		(effects
			(font
				(size 1.27 1.27)
			)
			(justify left bottom)
		)
	)
	(label "3V3_EN"
		(at 250.19 195.58 180)
		(effects
			(font
				(size 1.27 1.27)
			)
			(justify right bottom)
		)
	)
	(label "VCC_IN"
		(at 92.71 165.1 0)
		(effects
			(font
				(size 1.27 1.27)
			)
			(justify left bottom)
		)
	)
	(label "5V_VDD"
		(at 250.19 144.78 180)
		(effects
			(font
				(size 1.27 1.27)
			)
			(justify right bottom)
		)
	)
	(label "PG_{HP}"
		(at 143.51 262.89 0)
		(effects
			(font
				(size 1.27 1.27)
			)
			(justify left bottom)
		)
	)
	(label "5V_MODE2"
		(at 250.19 142.24 180)
		(effects
			(font
				(size 1.27 1.27)
			)
			(justify right bottom)
		)
	)
	(global_label "3V3_STDB"
		(shape input)
		(at 121.92 26.67 180)
		(fields_autoplaced yes)
		(effects
			(font
				(size 1.27 1.27)
			)
			(justify right)
		)
		(property "Intersheetrefs" "${INTERSHEET_REFS}"
			(at 109.7425 26.67 0)
			(effects
				(font
					(size 1.27 1.27)
				)
				(justify right)
			)
		)
	)
	(global_label "~{RESET}"
		(shape bidirectional)
		(at 270.51 39.37 0)
		(fields_autoplaced yes)
		(effects
			(font
				(size 1.27 1.27)
			)
			(justify left)
		)
		(property "Intersheetrefs" "${INTERSHEET_REFS}"
			(at 280.3516 39.37 0)
			(effects
				(font
					(size 1.27 1.27)
				)
				(justify left)
			)
		)
	)
	(global_label "3V3_STDB"
		(shape input)
		(at 82.55 26.67 180)
		(fields_autoplaced yes)
		(effects
			(font
				(size 1.27 1.27)
			)
			(justify right)
		)
		(property "Intersheetrefs" "${INTERSHEET_REFS}"
			(at 70.3725 26.67 0)
			(effects
				(font
					(size 1.27 1.27)
				)
				(justify right)
			)
		)
	)
	(global_label "~{RESET}"
		(shape bidirectional)
		(at 322.58 73.66 180)
		(fields_autoplaced yes)
		(effects
			(font
				(size 1.27 1.27)
			)
			(justify right)
		)
		(property "Intersheetrefs" "${INTERSHEET_REFS}"
			(at 312.7384 73.66 0)
			(effects
				(font
					(size 1.27 1.27)
				)
				(justify right)
			)
		)
	)
	(global_label "~{SHUTDOWN_REQ}"
		(shape input)
		(at 156.21 78.74 180)
		(fields_autoplaced yes)
		(effects
			(font
				(size 1.27 1.27)
			)
			(justify right)
		)
		(property "Intersheetrefs" "${INTERSHEET_REFS}"
			(at 138.2872 78.74 0)
			(effects
				(font
					(size 1.27 1.27)
				)
				(justify right)
			)
		)
	)
	(global_label "~{RESET}"
		(shape bidirectional)
		(at 254 76.2 0)
		(fields_autoplaced yes)
		(effects
			(font
				(size 1.27 1.27)
			)
			(justify left)
		)
		(property "Intersheetrefs" "${INTERSHEET_REFS}"
			(at 263.8416 76.2 0)
			(effects
				(font
					(size 1.27 1.27)
				)
				(justify left)
			)
		)
	)
	(global_label "USBPD2_HV"
		(shape bidirectional)
		(at 44.45 217.17 180)
		(fields_autoplaced yes)
		(effects
			(font
				(size 1.27 1.27)
			)
			(justify right)
		)
		(property "Intersheetrefs" "${INTERSHEET_REFS}"
			(at 29.4073 217.17 0)
			(effects
				(font
					(size 1.27 1.27)
				)
				(justify right)
			)
		)
	)
	(global_label "MODULE_ID"
		(shape output)
		(at 200.66 240.03 180)
		(effects
			(font
				(size 1.27 1.27)
			)
			(justify right)
		)
		(property "Intersheetrefs" "${INTERSHEET_REFS}"
			(at 187.96 240.03 0)
			(effects
				(font
					(size 1.27 1.27)
				)
				(justify right)
			)
		)
	)
	(global_label "POWER_EN"
		(shape output)
		(at 205.74 49.53 0)
		(fields_autoplaced yes)
		(effects
			(font
				(size 1.27 1.27)
			)
			(justify left)
		)
		(property "Intersheetrefs" "${INTERSHEET_REFS}"
			(at 218.6432 49.53 0)
			(effects
				(font
					(size 1.27 1.27)
				)
				(justify left)
			)
		)
	)
	(global_label "3V3_STDB"
		(shape input)
		(at 241.3 26.67 180)
		(fields_autoplaced yes)
		(effects
			(font
				(size 1.27 1.27)
			)
			(justify right)
		)
		(property "Intersheetrefs" "${INTERSHEET_REFS}"
			(at 229.1225 26.67 0)
			(effects
				(font
					(size 1.27 1.27)
				)
				(justify right)
			)
		)
	)
	(global_label "USBPD1_HV"
		(shape bidirectional)
		(at 44.45 209.55 180)
		(fields_autoplaced yes)
		(effects
			(font
				(size 1.27 1.27)
			)
			(justify right)
		)
		(property "Intersheetrefs" "${INTERSHEET_REFS}"
			(at 29.4073 209.55 0)
			(effects
				(font
					(size 1.27 1.27)
				)
				(justify right)
			)
		)
	)
	(global_label "PWR_SOFT"
		(shape input)
		(at 34.29 71.12 180)
		(fields_autoplaced yes)
		(effects
			(font
				(size 1.27 1.27)
			)
			(justify right)
		)
		(property "Intersheetrefs" "${INTERSHEET_REFS}"
			(at 21.7496 71.12 0)
			(effects
				(font
					(size 1.27 1.27)
				)
				(justify right)
			)
		)
	)
	(global_label "3V3_STDB"
		(shape input)
		(at 237.49 76.2 180)
		(fields_autoplaced yes)
		(effects
			(font
				(size 1.27 1.27)
			)
			(justify right)
		)
		(property "Intersheetrefs" "${INTERSHEET_REFS}"
			(at 225.3125 76.2 0)
			(effects
				(font
					(size 1.27 1.27)
				)
				(justify right)
			)
		)
	)
	(global_label "~{RESET}"
		(shape bidirectional)
		(at 365.76 152.4 180)
		(fields_autoplaced yes)
		(effects
			(font
				(size 1.27 1.27)
			)
			(justify right)
		)
		(property "Intersheetrefs" "${INTERSHEET_REFS}"
			(at 355.9184 152.4 0)
			(effects
				(font
					(size 1.27 1.27)
				)
				(justify right)
			)
		)
	)
	(global_label "~{RESET}"
		(shape bidirectional)
		(at 232.41 181.61 180)
		(fields_autoplaced yes)
		(effects
			(font
				(size 1.27 1.27)
			)
			(justify right)
		)
		(property "Intersheetrefs" "${INTERSHEET_REFS}"
			(at 222.5684 181.61 0)
			(effects
				(font
					(size 1.27 1.27)
				)
				(justify right)
			)
		)
	)
	(global_label "3V3_STDB"
		(shape input)
		(at 170.18 26.67 180)
		(fields_autoplaced yes)
		(effects
			(font
				(size 1.27 1.27)
			)
			(justify right)
		)
		(property "Intersheetrefs" "${INTERSHEET_REFS}"
			(at 158.0025 26.67 0)
			(effects
				(font
					(size 1.27 1.27)
				)
				(justify right)
			)
		)
	)
	(global_label "POE_OUTPUT"
		(shape input)
		(at 48.26 165.1 180)
		(fields_autoplaced yes)
		(effects
			(font
				(size 1.27 1.27)
			)
			(justify right)
		)
		(property "Intersheetrefs" "${INTERSHEET_REFS}"
			(at 33.361 165.1 0)
			(effects
				(font
					(size 1.27 1.27)
				)
				(justify right)
			)
		)
	)
	(global_label "3V3_STDB"
		(shape output)
		(at 384.81 30.48 0)
		(fields_autoplaced yes)
		(effects
			(font
				(size 1.27 1.27)
			)
			(justify left)
		)
		(property "Intersheetrefs" "${INTERSHEET_REFS}"
			(at 396.9875 30.48 0)
			(effects
				(font
					(size 1.27 1.27)
				)
				(justify left)
			)
		)
	)
	(symbol
		(lib_id "antmicroTVSDiodes:DF2S30FS_SOD")
		(at 38.1 119.38 270)
		(unit 1)
		(exclude_from_sim no)
		(in_bom yes)
		(on_board yes)
		(dnp no)
		(property "Reference" "D28"
			(at 39.37 120.65 90)
			(effects
				(font
					(size 1.27 1.27)
				)
				(justify left)
			)
		)
		(property "Value" "DF2S30FS_SOD"
			(at 22.86 140.97 0)
			(effects
				(font
					(size 1.27 1.27)
					(thickness 0.15)
				)
				(justify left bottom)
				(hide yes)
			)
		)
		(property "Footprint" "antmicro-footprints:SOD-923"
			(at 30.48 140.97 0)
			(effects
				(font
					(size 1.27 1.27)
					(thickness 0.15)
				)
				(justify left bottom)
				(hide yes)
			)
		)
		(property "Datasheet" "https://toshiba.semicon-storage.com/info/DF2S30FS_datasheet_en_20211216.pdf?did=11156&prodName=DF2S30FS"
			(at 27.94 140.97 0)
			(effects
				(font
					(size 1.27 1.27)
					(thickness 0.15)
				)
				(justify left bottom)
				(hide yes)
			)
		)
		(property "Description" ""
			(at 38.1 119.38 0)
			(effects
				(font
					(size 1.27 1.27)
				)
				(hide yes)
			)
		)
		(property "Manufacturer" "Toshiba"
			(at 25.4 140.97 0)
			(effects
				(font
					(size 1.27 1.27)
					(thickness 0.15)
				)
				(justify left bottom)
				(hide yes)
			)
		)
		(property "MPN" "DF2S30FS"
			(at 39.37 123.19 90)
			(effects
				(font
					(size 1.27 1.27)
					(thickness 0.15)
				)
				(justify left)
			)
		)
		(property "Author" "Antmicro"
			(at 20.32 140.97 0)
			(effects
				(font
					(size 1.27 1.27)
					(thickness 0.15)
				)
				(justify left bottom)
				(hide yes)
			)
		)
		(property "License" "Apache-2.0"
			(at 17.78 140.97 0)
			(effects
				(font
					(size 1.27 1.27)
					(thickness 0.15)
				)
				(justify left bottom)
				(hide yes)
			)
		)
		(pin "1"
		)
		(pin "2"
		)
		(instances
			(project "jetson-orin-baseboard"
				(path ""
					(reference "D28")
					(unit 1)
				)
			)
		)
	)
	(symbol
		(lib_id "antmicroTVSDiodes:ESD9X5.0ST5G")
		(at 358.14 135.89 270)
		(unit 1)
		(exclude_from_sim no)
		(in_bom yes)
		(on_board yes)
		(dnp no)
		(fields_autoplaced yes)
		(property "Reference" "D32"
			(at 356.235 137.16 90)
			(effects
				(font
					(size 1.27 1.27)
				)
				(justify right)
			)
		)
		(property "Value" "ESD9X5.0ST5G"
			(at 342.9 157.48 0)
			(effects
				(font
					(size 1.27 1.27)
					(thickness 0.15)
				)
				(justify left bottom)
				(hide yes)
			)
		)
		(property "Footprint" "antmicro-footprints:SOD-923"
			(at 350.52 157.48 0)
			(effects
				(font
					(size 1.27 1.27)
					(thickness 0.15)
				)
				(justify left bottom)
				(hide yes)
			)
		)
		(property "Datasheet" "https://www.onsemi.com/pdf/datasheet/esd9x3.3st5g-d.pdf"
			(at 347.98 157.48 0)
			(effects
				(font
					(size 1.27 1.27)
					(thickness 0.15)
				)
				(justify left bottom)
				(hide yes)
			)
		)
		(property "Description" ""
			(at 358.14 135.89 0)
			(effects
				(font
					(size 1.27 1.27)
				)
				(hide yes)
			)
		)
		(property "Manufacturer" "ON Semiconductor"
			(at 345.44 157.48 0)
			(effects
				(font
					(size 1.27 1.27)
					(thickness 0.15)
				)
				(justify left bottom)
				(hide yes)
			)
		)
		(property "MPN" "ESD9X5.0ST5G"
			(at 356.235 139.7 90)
			(effects
				(font
					(size 1.27 1.27)
					(thickness 0.15)
				)
				(justify right)
			)
		)
		(property "Author" "Antmicro"
			(at 340.36 157.48 0)
			(effects
				(font
					(size 1.27 1.27)
					(thickness 0.15)
				)
				(justify left bottom)
				(hide yes)
			)
		)
		(property "License" "Apache-2.0"
			(at 337.82 157.48 0)
			(effects
				(font
					(size 1.27 1.27)
					(thickness 0.15)
				)
				(justify left bottom)
				(hide yes)
			)
		)
		(pin "1"
		)
		(pin "2"
		)
		(instances
			(project "jetson-orin-baseboard"
				(path ""
					(reference "D32")
					(unit 1)
				)
			)
		)
	)
	(symbol
		(lib_id "antmicropower:GND")
		(at 321.31 213.36 0)
		(unit 1)
		(exclude_from_sim no)
		(in_bom yes)
		(on_board yes)
		(dnp no)
		(property "Reference" "#PWR0346"
			(at 321.31 219.71 0)
			(effects
				(font
					(size 1.27 1.27)
				)
				(justify left bottom)
				(hide yes)
			)
		)
		(property "Value" "GND"
			(at 321.31 217.17 0)
			(effects
				(font
					(size 1.27 1.27)
					(thickness 0.15)
				)
			)
		)
		(property "Footprint" ""
			(at 330.2 220.98 0)
			(effects
				(font
					(size 1.27 1.27)
					(thickness 0.15)
				)
				(justify left bottom)
				(hide yes)
			)
		)
		(property "Datasheet" ""
			(at 330.2 226.06 0)
			(effects
				(font
					(size 1.27 1.27)
					(thickness 0.15)
				)
				(justify left bottom)
				(hide yes)
			)
		)
		(property "Description" ""
			(at 321.31 213.36 0)
			(effects
				(font
					(size 1.27 1.27)
				)
				(hide yes)
			)
		)
		(property "Author" "Antmicro"
			(at 330.2 220.98 0)
			(effects
				(font
					(size 1.27 1.27)
					(thickness 0.15)
				)
				(justify left bottom)
				(hide yes)
			)
		)
		(property "License" "Apache-2.0"
			(at 330.2 223.52 0)
			(effects
				(font
					(size 1.27 1.27)
					(thickness 0.15)
				)
				(justify left bottom)
				(hide yes)
			)
		)
		(pin "1"
		)
		(instances
			(project "jetson-orin-baseboard"
				(path ""
					(reference "#PWR0346")
					(unit 1)
				)
			)
		)
	)
	(symbol
		(lib_id "antmicropower:GND")
		(at 43.18 81.28 0)
		(unit 1)
		(exclude_from_sim no)
		(in_bom yes)
		(on_board yes)
		(dnp no)
		(property "Reference" "#PWR0246"
			(at 43.18 87.63 0)
			(effects
				(font
					(size 1.27 1.27)
				)
				(justify left bottom)
				(hide yes)
			)
		)
		(property "Value" "GND"
			(at 43.18 85.09 0)
			(effects
				(font
					(size 1.27 1.27)
					(thickness 0.15)
				)
			)
		)
		(property "Footprint" ""
			(at 52.07 88.9 0)
			(effects
				(font
					(size 1.27 1.27)
					(thickness 0.15)
				)
				(justify left bottom)
				(hide yes)
			)
		)
		(property "Datasheet" ""
			(at 52.07 93.98 0)
			(effects
				(font
					(size 1.27 1.27)
					(thickness 0.15)
				)
				(justify left bottom)
				(hide yes)
			)
		)
		(property "Description" ""
			(at 43.18 81.28 0)
			(effects
				(font
					(size 1.27 1.27)
				)
				(hide yes)
			)
		)
		(property "Author" "Antmicro"
			(at 52.07 88.9 0)
			(effects
				(font
					(size 1.27 1.27)
					(thickness 0.15)
				)
				(justify left bottom)
				(hide yes)
			)
		)
		(property "License" "Apache-2.0"
			(at 52.07 91.44 0)
			(effects
				(font
					(size 1.27 1.27)
					(thickness 0.15)
				)
				(justify left bottom)
				(hide yes)
			)
		)
		(pin "1"
		)
		(instances
			(project "jetson-orin-baseboard"
				(path ""
					(reference "#PWR0246")
					(unit 1)
				)
			)
		)
	)
	(symbol
		(lib_id "antmicroCapacitors0402:C_1n_16V_X7R_0402")
		(at 262.89 274.32 90)
		(unit 1)
		(exclude_from_sim no)
		(in_bom yes)
		(on_board yes)
		(dnp no)
		(property "Reference" "C161"
			(at 263.525 269.875 90)
			(effects
				(font
					(size 1.27 1.27)
					(thickness 0.15)
				)
				(justify right)
			)
		)
		(property "Value" "C_1n_16V_X7R_0402"
			(at 273.05 259.08 0)
			(effects
				(font
					(size 1.27 1.27)
					(thickness 0.15)
				)
				(justify left bottom)
				(hide yes)
			)
		)
		(property "Footprint" "antmicro-footprints:C_0402_1005Metric"
			(at 275.59 259.08 0)
			(effects
				(font
					(size 1.27 1.27)
					(thickness 0.15)
				)
				(justify left bottom)
				(hide yes)
			)
		)
		(property "Datasheet" "https://www.kemet.com/en/us/capacitors/product/C0402C102J4RACTU.html"
			(at 278.13 259.08 0)
			(effects
				(font
					(size 1.27 1.27)
					(thickness 0.15)
				)
				(justify left bottom)
				(hide yes)
			)
		)
		(property "Description" "SMD Multilayer Ceramic Capacitor, 1nF, 16V, 0402, ±5%, X7R"
			(at 262.89 274.32 0)
			(effects
				(font
					(size 1.27 1.27)
				)
				(hide yes)
			)
		)
		(property "MPN" "C0402C102J4RACTU"
			(at 280.67 259.08 0)
			(effects
				(font
					(size 1.27 1.27)
					(thickness 0.15)
				)
				(justify left bottom)
				(hide yes)
			)
		)
		(property "Val" "1n"
			(at 263.525 273.685 90)
			(effects
				(font
					(size 1.27 1.27)
					(thickness 0.15)
				)
				(justify right)
			)
		)
		(property "Voltage" "16V"
			(at 283.21 259.08 0)
			(effects
				(font
					(size 1.27 1.27)
					(thickness 0.15)
				)
				(justify left bottom)
				(hide yes)
			)
		)
		(property "Dielectric" "X7R"
			(at 285.75 259.08 0)
			(effects
				(font
					(size 1.27 1.27)
					(thickness 0.15)
				)
				(justify left bottom)
				(hide yes)
			)
		)
		(property "Manufacturer" "KEMET"
			(at 288.29 259.08 0)
			(effects
				(font
					(size 1.27 1.27)
					(thickness 0.15)
				)
				(justify left bottom)
				(hide yes)
			)
		)
		(property "License" "Apache-2.0"
			(at 290.83 259.08 0)
			(effects
				(font
					(size 1.27 1.27)
					(thickness 0.15)
				)
				(justify left bottom)
				(hide yes)
			)
		)
		(property "Author" "Antmicro"
			(at 293.37 259.08 0)
			(effects
				(font
					(size 1.27 1.27)
					(thickness 0.15)
				)
				(justify left bottom)
				(hide yes)
			)
		)
		(pin "2"
		)
		(pin "1"
		)
		(instances
			(project ""
				(path ""
					(reference "C161")
					(unit 1)
				)
			)
		)
	)
	(symbol
		(lib_id "antmicroResistors0402:R_10k_0402")
		(at 151.13 49.53 90)
		(unit 1)
		(exclude_from_sim no)
		(in_bom yes)
		(on_board yes)
		(dnp no)
		(property "Reference" "R259"
			(at 152.4 45.72 90)
			(effects
				(font
					(size 1.27 1.27)
				)
				(justify right)
			)
		)
		(property "Value" "R_10k_0402"
			(at 163.83 29.21 0)
			(effects
				(font
					(size 1.27 1.27)
					(thickness 0.15)
				)
				(justify left bottom)
				(hide yes)
			)
		)
		(property "Footprint" "antmicro-footprints:R_0402_1005Metric"
			(at 166.37 29.21 0)
			(effects
				(font
					(size 1.27 1.27)
					(thickness 0.15)
				)
				(justify left bottom)
				(hide yes)
			)
		)
		(property "Datasheet" "https://www.bourns.com/docs/product-datasheets/cr.pdf"
			(at 168.91 29.21 0)
			(effects
				(font
					(size 1.27 1.27)
					(thickness 0.15)
				)
				(justify left bottom)
				(hide yes)
			)
		)
		(property "Description" ""
			(at 151.13 49.53 0)
			(effects
				(font
					(size 1.27 1.27)
				)
				(hide yes)
			)
		)
		(property "Manufacturer" "Bourns"
			(at 173.99 29.21 0)
			(effects
				(font
					(size 1.27 1.27)
					(thickness 0.15)
				)
				(justify left bottom)
				(hide yes)
			)
		)
		(property "MPN" "CR0402-FX-1002GLF"
			(at 171.45 29.21 0)
			(effects
				(font
					(size 1.27 1.27)
					(thickness 0.15)
				)
				(justify left bottom)
				(hide yes)
			)
		)
		(property "Val" "10k"
			(at 152.4 48.26 90)
			(effects
				(font
					(size 1.27 1.27)
					(thickness 0.15)
				)
				(justify right)
			)
		)
		(property "License" "Apache-2.0"
			(at 176.53 29.21 0)
			(effects
				(font
					(size 1.27 1.27)
					(thickness 0.15)
				)
				(justify left bottom)
				(hide yes)
			)
		)
		(property "Author" "Antmicro"
			(at 179.07 29.21 0)
			(effects
				(font
					(size 1.27 1.27)
					(thickness 0.15)
				)
				(justify left bottom)
				(hide yes)
			)
		)
		(property "Tolerance" "1%"
			(at 161.29 29.21 0)
			(effects
				(font
					(size 1.27 1.27)
				)
				(justify left bottom)
				(hide yes)
			)
		)
		(pin "1"
		)
		(pin "2"
		)
		(instances
			(project "jetson-orin-baseboard"
				(path ""
					(reference "R259")
					(unit 1)
				)
			)
		)
	)
	(symbol
		(lib_id "antmicropower:+5V")
		(at 274.32 250.19 0)
		(unit 1)
		(exclude_from_sim no)
		(in_bom yes)
		(on_board yes)
		(dnp no)
		(property "Reference" "#PWR05"
			(at 274.32 254 0)
			(effects
				(font
					(size 1.27 1.27)
				)
				(justify left bottom)
				(hide yes)
			)
		)
		(property "Value" "VDD_SoM"
			(at 274.32 246.38 0)
			(effects
				(font
					(size 1.27 1.27)
					(thickness 0.15)
				)
			)
		)
		(property "Footprint" ""
			(at 289.56 257.81 0)
			(effects
				(font
					(size 1.27 1.27)
					(thickness 0.15)
				)
				(justify left bottom)
				(hide yes)
			)
		)
		(property "Datasheet" ""
			(at 289.56 260.35 0)
			(effects
				(font
					(size 1.27 1.27)
					(thickness 0.15)
				)
				(justify left bottom)
				(hide yes)
			)
		)
		(property "Description" ""
			(at 274.32 250.19 0)
			(effects
				(font
					(size 1.27 1.27)
				)
				(hide yes)
			)
		)
		(property "Author" "Antmicro"
			(at 289.56 257.81 0)
			(effects
				(font
					(size 1.27 1.27)
					(thickness 0.15)
				)
				(justify left bottom)
				(hide yes)
			)
		)
		(property "License" "Apache-2.0"
			(at 289.56 260.35 0)
			(effects
				(font
					(size 1.27 1.27)
					(thickness 0.15)
				)
				(justify left bottom)
				(hide yes)
			)
		)
		(pin "1"
		)
		(instances
			(project "jetson-orin-baseboard"
				(path ""
					(reference "#PWR05")
					(unit 1)
				)
			)
		)
	)
	(symbol
		(lib_id "antmicroResistors0402:R_4k7_0402")
		(at 109.22 171.45 90)
		(unit 1)
		(exclude_from_sim no)
		(in_bom yes)
		(on_board yes)
		(dnp no)
		(property "Reference" "R164"
			(at 110.49 167.64 90)
			(effects
				(font
					(size 1.27 1.27)
				)
				(justify right)
			)
		)
		(property "Value" "R_4k7_0402"
			(at 121.92 151.13 0)
			(effects
				(font
					(size 1.27 1.27)
					(thickness 0.15)
				)
				(justify left bottom)
				(hide yes)
			)
		)
		(property "Footprint" "antmicro-footprints:R_0402_1005Metric"
			(at 124.46 151.13 0)
			(effects
				(font
					(size 1.27 1.27)
					(thickness 0.15)
				)
				(justify left bottom)
				(hide yes)
			)
		)
		(property "Datasheet" "https://www.bourns.com/docs/product-datasheets/cr.pdf"
			(at 127 151.13 0)
			(effects
				(font
					(size 1.27 1.27)
					(thickness 0.15)
				)
				(justify left bottom)
				(hide yes)
			)
		)
		(property "Description" ""
			(at 109.22 171.45 0)
			(effects
				(font
					(size 1.27 1.27)
				)
				(hide yes)
			)
		)
		(property "Manufacturer" "Bourns"
			(at 132.08 151.13 0)
			(effects
				(font
					(size 1.27 1.27)
					(thickness 0.15)
				)
				(justify left bottom)
				(hide yes)
			)
		)
		(property "MPN" "CR0402-FX-4701GLF"
			(at 129.54 151.13 0)
			(effects
				(font
					(size 1.27 1.27)
					(thickness 0.15)
				)
				(justify left bottom)
				(hide yes)
			)
		)
		(property "Val" "4k7"
			(at 110.49 170.18 90)
			(effects
				(font
					(size 1.27 1.27)
					(thickness 0.15)
				)
				(justify right)
			)
		)
		(property "License" "Apache-2.0"
			(at 134.62 151.13 0)
			(effects
				(font
					(size 1.27 1.27)
					(thickness 0.15)
				)
				(justify left bottom)
				(hide yes)
			)
		)
		(property "Author" "Antmicro"
			(at 137.16 151.13 0)
			(effects
				(font
					(size 1.27 1.27)
					(thickness 0.15)
				)
				(justify left bottom)
				(hide yes)
			)
		)
		(property "Tolerance" "1%"
			(at 119.38 151.13 0)
			(effects
				(font
					(size 1.27 1.27)
				)
				(justify left bottom)
				(hide yes)
			)
		)
		(pin "1"
		)
		(pin "2"
		)
		(instances
			(project "jetson-orin-baseboard"
				(path ""
					(reference "R164")
					(unit 1)
				)
			)
		)
	)
	(symbol
		(lib_id "antmicroTVSDiodes:ESD9X5.0ST5G")
		(at 386.08 72.39 270)
		(unit 1)
		(exclude_from_sim no)
		(in_bom yes)
		(on_board yes)
		(dnp no)
		(property "Reference" "D31"
			(at 387.35 73.66 90)
			(effects
				(font
					(size 1.27 1.27)
				)
				(justify left)
			)
		)
		(property "Value" "ESD9X5.0ST5G"
			(at 370.84 93.98 0)
			(effects
				(font
					(size 1.27 1.27)
					(thickness 0.15)
				)
				(justify left bottom)
				(hide yes)
			)
		)
		(property "Footprint" "antmicro-footprints:SOD-923"
			(at 378.46 93.98 0)
			(effects
				(font
					(size 1.27 1.27)
					(thickness 0.15)
				)
				(justify left bottom)
				(hide yes)
			)
		)
		(property "Datasheet" "https://www.onsemi.com/pdf/datasheet/esd9x3.3st5g-d.pdf"
			(at 375.92 93.98 0)
			(effects
				(font
					(size 1.27 1.27)
					(thickness 0.15)
				)
				(justify left bottom)
				(hide yes)
			)
		)
		(property "Description" ""
			(at 386.08 72.39 0)
			(effects
				(font
					(size 1.27 1.27)
				)
				(hide yes)
			)
		)
		(property "Manufacturer" "ON Semiconductor"
			(at 373.38 93.98 0)
			(effects
				(font
					(size 1.27 1.27)
					(thickness 0.15)
				)
				(justify left bottom)
				(hide yes)
			)
		)
		(property "MPN" "ESD9X5.0ST5G"
			(at 387.35 76.2 90)
			(effects
				(font
					(size 1.27 1.27)
					(thickness 0.15)
				)
				(justify left)
			)
		)
		(property "Author" "Antmicro"
			(at 368.3 93.98 0)
			(effects
				(font
					(size 1.27 1.27)
					(thickness 0.15)
				)
				(justify left bottom)
				(hide yes)
			)
		)
		(property "License" "Apache-2.0"
			(at 365.76 93.98 0)
			(effects
				(font
					(size 1.27 1.27)
					(thickness 0.15)
				)
				(justify left bottom)
				(hide yes)
			)
		)
		(pin "1"
		)
		(pin "2"
		)
		(instances
			(project "jetson-orin-baseboard"
				(path ""
					(reference "D31")
					(unit 1)
				)
			)
		)
	)
	(symbol
		(lib_id "antmicroCapacitors0402:C_1u_0402")
		(at 365.76 77.47 90)
		(unit 1)
		(exclude_from_sim no)
		(in_bom yes)
		(on_board yes)
		(dnp no)
		(property "Reference" "C142"
			(at 367.665 73.66 90)
			(effects
				(font
					(size 1.27 1.27)
				)
				(justify right)
			)
		)
		(property "Value" "C_1u_0402"
			(at 375.92 57.15 0)
			(effects
				(font
					(size 1.27 1.27)
					(thickness 0.15)
				)
				(justify left bottom)
				(hide yes)
			)
		)
		(property "Footprint" "antmicro-footprints:C_0402_1005Metric"
			(at 378.46 57.15 0)
			(effects
				(font
					(size 1.27 1.27)
					(thickness 0.15)
				)
				(justify left bottom)
				(hide yes)
			)
		)
		(property "Datasheet" "https://product.tdk.com/en/search/capacitor/ceramic/mlcc/info?part_no=C1005X6S1A105K050BC"
			(at 381 57.15 0)
			(effects
				(font
					(size 1.27 1.27)
					(thickness 0.15)
				)
				(justify left bottom)
				(hide yes)
			)
		)
		(property "Description" ""
			(at 365.76 77.47 0)
			(effects
				(font
					(size 1.27 1.27)
				)
				(hide yes)
			)
		)
		(property "Manufacturer" "TDK"
			(at 386.08 57.15 0)
			(effects
				(font
					(size 1.27 1.27)
					(thickness 0.15)
				)
				(justify left bottom)
				(hide yes)
			)
		)
		(property "MPN" "C1005X6S1A105K050BC"
			(at 383.54 57.15 0)
			(effects
				(font
					(size 1.27 1.27)
					(thickness 0.15)
				)
				(justify left bottom)
				(hide yes)
			)
		)
		(property "Val" "1u"
			(at 367.665 76.2 90)
			(effects
				(font
					(size 1.27 1.27)
					(thickness 0.15)
				)
				(justify right)
			)
		)
		(property "License" "Apache-2.0"
			(at 388.62 57.15 0)
			(effects
				(font
					(size 1.27 1.27)
					(thickness 0.15)
				)
				(justify left bottom)
				(hide yes)
			)
		)
		(property "Author" "Antmicro"
			(at 391.16 57.15 0)
			(effects
				(font
					(size 1.27 1.27)
					(thickness 0.15)
				)
				(justify left bottom)
				(hide yes)
			)
		)
		(property "Voltage" ""
			(at 393.7 57.15 0)
			(effects
				(font
					(size 1.27 1.27)
				)
				(justify left bottom)
				(hide yes)
			)
		)
		(property "Dielectric" ""
			(at 396.24 57.15 0)
			(effects
				(font
					(size 1.27 1.27)
				)
				(justify left bottom)
				(hide yes)
			)
		)
		(pin "1"
		)
		(pin "2"
		)
		(instances
			(project "jetson-orin-baseboard"
				(path ""
					(reference "C142")
					(unit 1)
				)
			)
		)
	)
	(symbol
		(lib_id "antmicroResistors0402:R_499k_0402")
		(at 214.63 153.67 90)
		(unit 1)
		(exclude_from_sim no)
		(in_bom yes)
		(on_board yes)
		(dnp no)
		(property "Reference" "R237"
			(at 215.9 149.86 90)
			(effects
				(font
					(size 1.27 1.27)
					(thickness 0.15)
				)
				(justify right)
			)
		)
		(property "Value" "R_499k_0402"
			(at 227.33 133.35 0)
			(effects
				(font
					(size 1.27 1.27)
					(thickness 0.15)
				)
				(justify left bottom)
				(hide yes)
			)
		)
		(property "Footprint" "antmicro-footprints:R_0402_1005Metric"
			(at 229.87 133.35 0)
			(effects
				(font
					(size 1.27 1.27)
					(thickness 0.15)
				)
				(justify left bottom)
				(hide yes)
			)
		)
		(property "Datasheet" "https://www.mouser.com/datasheet/2/54/cr-1858361.pdf"
			(at 232.41 133.35 0)
			(effects
				(font
					(size 1.27 1.27)
					(thickness 0.15)
				)
				(justify left bottom)
				(hide yes)
			)
		)
		(property "Description" ""
			(at 214.63 153.67 0)
			(effects
				(font
					(size 1.27 1.27)
				)
				(hide yes)
			)
		)
		(property "MPN" "CR0402-FX-4993GLF"
			(at 234.95 133.35 0)
			(effects
				(font
					(size 1.27 1.27)
					(thickness 0.15)
				)
				(justify left bottom)
				(hide yes)
			)
		)
		(property "Manufacturer" "Bourns"
			(at 237.49 133.35 0)
			(effects
				(font
					(size 1.27 1.27)
					(thickness 0.15)
				)
				(justify left bottom)
				(hide yes)
			)
		)
		(property "License" "Apache-2.0"
			(at 240.03 133.35 0)
			(effects
				(font
					(size 1.27 1.27)
					(thickness 0.15)
				)
				(justify left bottom)
				(hide yes)
			)
		)
		(property "Author" "Antmicro"
			(at 242.57 133.35 0)
			(effects
				(font
					(size 1.27 1.27)
					(thickness 0.15)
				)
				(justify left bottom)
				(hide yes)
			)
		)
		(property "Val" "499k"
			(at 215.9 152.4 90)
			(effects
				(font
					(size 1.27 1.27)
					(thickness 0.15)
				)
				(justify right)
			)
		)
		(property "Tolerance" "1%"
			(at 224.79 133.35 0)
			(effects
				(font
					(size 1.27 1.27)
				)
				(justify left bottom)
				(hide yes)
			)
		)
		(pin "2"
		)
		(pin "1"
		)
		(instances
			(project "jetson-orin-baseboard"
				(path ""
					(reference "R237")
					(unit 1)
				)
			)
		)
	)
	(symbol
		(lib_id "antmicropower:GND")
		(at 166.37 181.61 0)
		(unit 1)
		(exclude_from_sim no)
		(in_bom yes)
		(on_board yes)
		(dnp no)
		(property "Reference" "#PWR0312"
			(at 166.37 187.96 0)
			(effects
				(font
					(size 1.27 1.27)
				)
				(justify left bottom)
				(hide yes)
			)
		)
		(property "Value" "GND"
			(at 166.37 185.42 0)
			(effects
				(font
					(size 1.27 1.27)
					(thickness 0.15)
				)
			)
		)
		(property "Footprint" ""
			(at 175.26 189.23 0)
			(effects
				(font
					(size 1.27 1.27)
					(thickness 0.15)
				)
				(justify left bottom)
				(hide yes)
			)
		)
		(property "Datasheet" ""
			(at 175.26 194.31 0)
			(effects
				(font
					(size 1.27 1.27)
					(thickness 0.15)
				)
				(justify left bottom)
				(hide yes)
			)
		)
		(property "Description" ""
			(at 166.37 181.61 0)
			(effects
				(font
					(size 1.27 1.27)
				)
				(hide yes)
			)
		)
		(property "Author" "Antmicro"
			(at 175.26 189.23 0)
			(effects
				(font
					(size 1.27 1.27)
					(thickness 0.15)
				)
				(justify left bottom)
				(hide yes)
			)
		)
		(property "License" "Apache-2.0"
			(at 175.26 191.77 0)
			(effects
				(font
					(size 1.27 1.27)
					(thickness 0.15)
				)
				(justify left bottom)
				(hide yes)
			)
		)
		(pin "1"
		)
		(instances
			(project "jetson-orin-baseboard"
				(path ""
					(reference "#PWR0312")
					(unit 1)
				)
			)
		)
	)
	(symbol
		(lib_id "antmicropower:GND")
		(at 213.36 279.4 0)
		(unit 1)
		(exclude_from_sim no)
		(in_bom yes)
		(on_board yes)
		(dnp no)
		(property "Reference" "#PWR0367"
			(at 213.36 285.75 0)
			(effects
				(font
					(size 1.27 1.27)
				)
				(justify left bottom)
				(hide yes)
			)
		)
		(property "Value" "GND"
			(at 213.36 283.21 0)
			(effects
				(font
					(size 1.27 1.27)
					(thickness 0.15)
				)
			)
		)
		(property "Footprint" ""
			(at 222.25 287.02 0)
			(effects
				(font
					(size 1.27 1.27)
					(thickness 0.15)
				)
				(justify left bottom)
				(hide yes)
			)
		)
		(property "Datasheet" ""
			(at 222.25 292.1 0)
			(effects
				(font
					(size 1.27 1.27)
					(thickness 0.15)
				)
				(justify left bottom)
				(hide yes)
			)
		)
		(property "Description" ""
			(at 213.36 279.4 0)
			(effects
				(font
					(size 1.27 1.27)
				)
				(hide yes)
			)
		)
		(property "Author" "Antmicro"
			(at 222.25 287.02 0)
			(effects
				(font
					(size 1.27 1.27)
					(thickness 0.15)
				)
				(justify left bottom)
				(hide yes)
			)
		)
		(property "License" "Apache-2.0"
			(at 222.25 289.56 0)
			(effects
				(font
					(size 1.27 1.27)
					(thickness 0.15)
				)
				(justify left bottom)
				(hide yes)
			)
		)
		(pin "1"
		)
		(instances
			(project "jetson-orin-baseboard"
				(path ""
					(reference "#PWR0367")
					(unit 1)
				)
			)
		)
	)
	(symbol
		(lib_id "antmicropower:GND")
		(at 360.68 213.36 0)
		(unit 1)
		(exclude_from_sim no)
		(in_bom yes)
		(on_board yes)
		(dnp no)
		(property "Reference" "#PWR0349"
			(at 360.68 219.71 0)
			(effects
				(font
					(size 1.27 1.27)
				)
				(justify left bottom)
				(hide yes)
			)
		)
		(property "Value" "GND"
			(at 360.68 217.17 0)
			(effects
				(font
					(size 1.27 1.27)
					(thickness 0.15)
				)
			)
		)
		(property "Footprint" ""
			(at 369.57 220.98 0)
			(effects
				(font
					(size 1.27 1.27)
					(thickness 0.15)
				)
				(justify left bottom)
				(hide yes)
			)
		)
		(property "Datasheet" ""
			(at 369.57 226.06 0)
			(effects
				(font
					(size 1.27 1.27)
					(thickness 0.15)
				)
				(justify left bottom)
				(hide yes)
			)
		)
		(property "Description" ""
			(at 360.68 213.36 0)
			(effects
				(font
					(size 1.27 1.27)
				)
				(hide yes)
			)
		)
		(property "Author" "Antmicro"
			(at 369.57 220.98 0)
			(effects
				(font
					(size 1.27 1.27)
					(thickness 0.15)
				)
				(justify left bottom)
				(hide yes)
			)
		)
		(property "License" "Apache-2.0"
			(at 369.57 223.52 0)
			(effects
				(font
					(size 1.27 1.27)
					(thickness 0.15)
				)
				(justify left bottom)
				(hide yes)
			)
		)
		(pin "1"
		)
		(instances
			(project "jetson-orin-baseboard"
				(path ""
					(reference "#PWR0349")
					(unit 1)
				)
			)
		)
	)
	(symbol
		(lib_id "antmicropower:+1V8")
		(at 397.51 67.31 0)
		(unit 1)
		(exclude_from_sim no)
		(in_bom yes)
		(on_board yes)
		(dnp no)
		(property "Reference" "#PWR0293"
			(at 397.51 71.12 0)
			(effects
				(font
					(size 1.27 1.27)
				)
				(justify left bottom)
				(hide yes)
			)
		)
		(property "Value" "+1V8"
			(at 394.335 63.5 0)
			(effects
				(font
					(size 1.27 1.27)
					(thickness 0.15)
				)
				(justify left)
			)
		)
		(property "Footprint" ""
			(at 412.75 74.93 0)
			(effects
				(font
					(size 1.27 1.27)
					(thickness 0.15)
				)
				(justify left bottom)
				(hide yes)
			)
		)
		(property "Datasheet" ""
			(at 412.75 77.47 0)
			(effects
				(font
					(size 1.27 1.27)
					(thickness 0.15)
				)
				(justify left bottom)
				(hide yes)
			)
		)
		(property "Description" ""
			(at 397.51 67.31 0)
			(effects
				(font
					(size 1.27 1.27)
				)
				(hide yes)
			)
		)
		(property "Author" "Antmicro"
			(at 412.75 72.39 0)
			(effects
				(font
					(size 1.27 1.27)
					(thickness 0.15)
				)
				(justify left bottom)
				(hide yes)
			)
		)
		(property "License" "Apache-2.0"
			(at 412.75 74.93 0)
			(effects
				(font
					(size 1.27 1.27)
					(thickness 0.15)
				)
				(justify left bottom)
				(hide yes)
			)
		)
		(pin "1"
		)
		(instances
			(project "jetson-orin-baseboard"
				(path ""
					(reference "#PWR0293")
					(unit 1)
				)
			)
		)
	)
	(symbol
		(lib_id "antmicropower:GND")
		(at 313.69 154.94 0)
		(unit 1)
		(exclude_from_sim no)
		(in_bom yes)
		(on_board yes)
		(dnp no)
		(property "Reference" "#PWR0189"
			(at 313.69 161.29 0)
			(effects
				(font
					(size 1.27 1.27)
				)
				(justify left bottom)
				(hide yes)
			)
		)
		(property "Value" "GND"
			(at 313.69 158.75 0)
			(effects
				(font
					(size 1.27 1.27)
					(thickness 0.15)
				)
			)
		)
		(property "Footprint" ""
			(at 322.58 162.56 0)
			(effects
				(font
					(size 1.27 1.27)
					(thickness 0.15)
				)
				(justify left bottom)
				(hide yes)
			)
		)
		(property "Datasheet" ""
			(at 322.58 167.64 0)
			(effects
				(font
					(size 1.27 1.27)
					(thickness 0.15)
				)
				(justify left bottom)
				(hide yes)
			)
		)
		(property "Description" ""
			(at 313.69 154.94 0)
			(effects
				(font
					(size 1.27 1.27)
				)
				(hide yes)
			)
		)
		(property "Author" "Antmicro"
			(at 322.58 162.56 0)
			(effects
				(font
					(size 1.27 1.27)
					(thickness 0.15)
				)
				(justify left bottom)
				(hide yes)
			)
		)
		(property "License" "Apache-2.0"
			(at 322.58 165.1 0)
			(effects
				(font
					(size 1.27 1.27)
					(thickness 0.15)
				)
				(justify left bottom)
				(hide yes)
			)
		)
		(pin "1"
		)
		(instances
			(project "jetson-orin-baseboard"
				(path ""
					(reference "#PWR0189")
					(unit 1)
				)
			)
		)
	)
	(symbol
		(lib_id "antmicroCapacitors0603:C_10u_25V_0603")
		(at 318.77 36.83 90)
		(unit 1)
		(exclude_from_sim no)
		(in_bom yes)
		(on_board yes)
		(dnp no)
		(property "Reference" "C134"
			(at 320.675 33.02 90)
			(effects
				(font
					(size 1.27 1.27)
				)
				(justify right)
			)
		)
		(property "Value" "C_10u_25V_0603"
			(at 328.93 16.51 0)
			(effects
				(font
					(size 1.27 1.27)
					(thickness 0.15)
				)
				(justify left bottom)
				(hide yes)
			)
		)
		(property "Footprint" "antmicro-footprints:C_0603_1608Metric"
			(at 331.47 16.51 0)
			(effects
				(font
					(size 1.27 1.27)
					(thickness 0.15)
				)
				(justify left bottom)
				(hide yes)
			)
		)
		(property "Datasheet" "https://product.tdk.com/en/search/capacitor/ceramic/mlcc/info?part_no=C1608X5R1E106M080AC"
			(at 334.01 16.51 0)
			(effects
				(font
					(size 1.27 1.27)
					(thickness 0.15)
				)
				(justify left bottom)
				(hide yes)
			)
		)
		(property "Description" ""
			(at 318.77 36.83 0)
			(effects
				(font
					(size 1.27 1.27)
				)
				(hide yes)
			)
		)
		(property "Manufacturer" "TDK"
			(at 339.09 16.51 0)
			(effects
				(font
					(size 1.27 1.27)
					(thickness 0.15)
				)
				(justify left bottom)
				(hide yes)
			)
		)
		(property "MPN" "C1608X5R1E106M080AC"
			(at 336.55 16.51 0)
			(effects
				(font
					(size 1.27 1.27)
					(thickness 0.15)
				)
				(justify left bottom)
				(hide yes)
			)
		)
		(property "Val" "10u"
			(at 320.675 35.56 90)
			(effects
				(font
					(size 1.27 1.27)
					(thickness 0.15)
				)
				(justify right)
			)
		)
		(property "License" "Apache-2.0"
			(at 341.63 16.51 0)
			(effects
				(font
					(size 1.27 1.27)
					(thickness 0.15)
				)
				(justify left bottom)
				(hide yes)
			)
		)
		(property "Author" "Antmicro"
			(at 344.17 16.51 0)
			(effects
				(font
					(size 1.27 1.27)
					(thickness 0.15)
				)
				(justify left bottom)
				(hide yes)
			)
		)
		(property "Voltage" "25V"
			(at 346.71 16.51 0)
			(effects
				(font
					(size 1.27 1.27)
				)
				(justify left bottom)
				(hide yes)
			)
		)
		(property "Dielectric" ""
			(at 349.25 16.51 0)
			(effects
				(font
					(size 1.27 1.27)
				)
				(justify left bottom)
				(hide yes)
			)
		)
		(pin "1"
		)
		(pin "2"
		)
		(instances
			(project "jetson-orin-baseboard"
				(path ""
					(reference "C134")
					(unit 1)
				)
			)
		)
	)
	(symbol
		(lib_id "antmicroPMICORControllersIdealDiodes:TPS259474ARPWR")
		(at 214.63 262.89 0)
		(unit 1)
		(exclude_from_sim no)
		(in_bom yes)
		(on_board yes)
		(dnp no)
		(fields_autoplaced yes)
		(property "Reference" "U29"
			(at 226.06 255.27 0)
			(effects
				(font
					(size 1.27 1.27)
					(thickness 0.15)
				)
			)
		)
		(property "Value" "TPS259474"
			(at 250.19 270.51 0)
			(effects
				(font
					(size 1.27 1.27)
					(thickness 0.15)
				)
				(justify left bottom)
				(hide yes)
			)
		)
		(property "Footprint" "antmicro-footprints:VQFN-HR-10_2x2mm"
			(at 250.19 273.05 0)
			(effects
				(font
					(size 1.27 1.27)
					(thickness 0.15)
				)
				(justify left bottom)
				(hide yes)
			)
		)
		(property "Datasheet" "https://www.ti.com/lit/ds/symlink/tps25947.pdf"
			(at 250.19 275.59 0)
			(effects
				(font
					(size 1.27 1.27)
					(thickness 0.15)
				)
				(justify left bottom)
				(hide yes)
			)
		)
		(property "Description" "Reverse Current Blocking eFuse with Input Reverse Polarity Protection, 5.5A, 23V, -40 to 125 Deg C, VQFN-HR-10"
			(at 250.19 278.13 0)
			(effects
				(font
					(size 1.27 1.27)
					(thickness 0.15)
				)
				(justify left bottom)
				(hide yes)
			)
		)
		(property "MPN" "TPS259474ARPWR"
			(at 226.06 257.81 0)
			(effects
				(font
					(size 1.27 1.27)
					(thickness 0.15)
				)
			)
		)
		(property "Manufacturer" "Texas Instruments"
			(at 250.19 280.67 0)
			(effects
				(font
					(size 1.27 1.27)
					(thickness 0.15)
				)
				(justify left bottom)
				(hide yes)
			)
		)
		(property "Author" "Antmicro"
			(at 250.19 283.21 0)
			(effects
				(font
					(size 1.27 1.27)
					(thickness 0.15)
				)
				(justify left bottom)
				(hide yes)
			)
		)
		(property "License" "Apache-2.0"
			(at 250.19 285.75 0)
			(effects
				(font
					(size 1.27 1.27)
					(thickness 0.15)
				)
				(justify left bottom)
				(hide yes)
			)
		)
		(pin "1"
		)
		(pin "10"
		)
		(pin "9"
		)
		(pin "7"
		)
		(pin "8"
		)
		(pin "3"
		)
		(pin "4"
		)
		(pin "2"
		)
		(pin "6"
		)
		(pin "5"
		)
		(instances
			(project "jetson-orin-baseboard"
				(path ""
					(reference "U29")
					(unit 1)
				)
			)
		)
	)
	(symbol
		(lib_id "antmicroResistors0402:R_499k_0402")
		(at 223.52 153.67 90)
		(unit 1)
		(exclude_from_sim no)
		(in_bom yes)
		(on_board yes)
		(dnp no)
		(property "Reference" "R239"
			(at 224.79 149.86 90)
			(effects
				(font
					(size 1.27 1.27)
					(thickness 0.15)
				)
				(justify right)
			)
		)
		(property "Value" "R_499k_0402"
			(at 236.22 133.35 0)
			(effects
				(font
					(size 1.27 1.27)
					(thickness 0.15)
				)
				(justify left bottom)
				(hide yes)
			)
		)
		(property "Footprint" "antmicro-footprints:R_0402_1005Metric"
			(at 238.76 133.35 0)
			(effects
				(font
					(size 1.27 1.27)
					(thickness 0.15)
				)
				(justify left bottom)
				(hide yes)
			)
		)
		(property "Datasheet" "https://www.mouser.com/datasheet/2/54/cr-1858361.pdf"
			(at 241.3 133.35 0)
			(effects
				(font
					(size 1.27 1.27)
					(thickness 0.15)
				)
				(justify left bottom)
				(hide yes)
			)
		)
		(property "Description" ""
			(at 223.52 153.67 0)
			(effects
				(font
					(size 1.27 1.27)
				)
				(hide yes)
			)
		)
		(property "MPN" "CR0402-FX-4993GLF"
			(at 243.84 133.35 0)
			(effects
				(font
					(size 1.27 1.27)
					(thickness 0.15)
				)
				(justify left bottom)
				(hide yes)
			)
		)
		(property "Manufacturer" "Bourns"
			(at 246.38 133.35 0)
			(effects
				(font
					(size 1.27 1.27)
					(thickness 0.15)
				)
				(justify left bottom)
				(hide yes)
			)
		)
		(property "License" "Apache-2.0"
			(at 248.92 133.35 0)
			(effects
				(font
					(size 1.27 1.27)
					(thickness 0.15)
				)
				(justify left bottom)
				(hide yes)
			)
		)
		(property "Author" "Antmicro"
			(at 251.46 133.35 0)
			(effects
				(font
					(size 1.27 1.27)
					(thickness 0.15)
				)
				(justify left bottom)
				(hide yes)
			)
		)
		(property "Val" "499k"
			(at 224.79 152.4 90)
			(effects
				(font
					(size 1.27 1.27)
					(thickness 0.15)
				)
				(justify right)
			)
		)
		(property "Tolerance" "1%"
			(at 233.68 133.35 0)
			(effects
				(font
					(size 1.27 1.27)
				)
				(justify left bottom)
				(hide yes)
			)
		)
		(pin "2"
		)
		(pin "1"
		)
		(instances
			(project "jetson-orin-baseboard"
				(path ""
					(reference "R239")
					(unit 1)
				)
			)
		)
	)
	(symbol
		(lib_id "antmicropower:GND")
		(at 223.52 120.65 0)
		(unit 1)
		(exclude_from_sim no)
		(in_bom yes)
		(on_board yes)
		(dnp no)
		(property "Reference" "#PWR0344"
			(at 223.52 127 0)
			(effects
				(font
					(size 1.27 1.27)
				)
				(justify left bottom)
				(hide yes)
			)
		)
		(property "Value" "GND"
			(at 223.52 124.46 0)
			(effects
				(font
					(size 1.27 1.27)
					(thickness 0.15)
				)
			)
		)
		(property "Footprint" ""
			(at 232.41 128.27 0)
			(effects
				(font
					(size 1.27 1.27)
					(thickness 0.15)
				)
				(justify left bottom)
				(hide yes)
			)
		)
		(property "Datasheet" ""
			(at 232.41 133.35 0)
			(effects
				(font
					(size 1.27 1.27)
					(thickness 0.15)
				)
				(justify left bottom)
				(hide yes)
			)
		)
		(property "Description" ""
			(at 223.52 120.65 0)
			(effects
				(font
					(size 1.27 1.27)
				)
				(hide yes)
			)
		)
		(property "Author" "Antmicro"
			(at 232.41 128.27 0)
			(effects
				(font
					(size 1.27 1.27)
					(thickness 0.15)
				)
				(justify left bottom)
				(hide yes)
			)
		)
		(property "License" "Apache-2.0"
			(at 232.41 130.81 0)
			(effects
				(font
					(size 1.27 1.27)
					(thickness 0.15)
				)
				(justify left bottom)
				(hide yes)
			)
		)
		(pin "1"
		)
		(instances
			(project "jetson-orin-baseboard"
				(path ""
					(reference "#PWR0344")
					(unit 1)
				)
			)
		)
	)
	(symbol
		(lib_id "antmicroResistors0402:R_10k_0402")
		(at 156.21 171.45 90)
		(unit 1)
		(exclude_from_sim no)
		(in_bom yes)
		(on_board yes)
		(dnp no)
		(property "Reference" "R188"
			(at 157.48 167.64 90)
			(effects
				(font
					(size 1.27 1.27)
				)
				(justify right)
			)
		)
		(property "Value" "R_10k_0402"
			(at 168.91 151.13 0)
			(effects
				(font
					(size 1.27 1.27)
					(thickness 0.15)
				)
				(justify left bottom)
				(hide yes)
			)
		)
		(property "Footprint" "antmicro-footprints:R_0402_1005Metric"
			(at 171.45 151.13 0)
			(effects
				(font
					(size 1.27 1.27)
					(thickness 0.15)
				)
				(justify left bottom)
				(hide yes)
			)
		)
		(property "Datasheet" "https://www.bourns.com/docs/product-datasheets/cr.pdf"
			(at 173.99 151.13 0)
			(effects
				(font
					(size 1.27 1.27)
					(thickness 0.15)
				)
				(justify left bottom)
				(hide yes)
			)
		)
		(property "Description" ""
			(at 156.21 171.45 0)
			(effects
				(font
					(size 1.27 1.27)
				)
				(hide yes)
			)
		)
		(property "Manufacturer" "Bourns"
			(at 179.07 151.13 0)
			(effects
				(font
					(size 1.27 1.27)
					(thickness 0.15)
				)
				(justify left bottom)
				(hide yes)
			)
		)
		(property "MPN" "CR0402-FX-1002GLF"
			(at 176.53 151.13 0)
			(effects
				(font
					(size 1.27 1.27)
					(thickness 0.15)
				)
				(justify left bottom)
				(hide yes)
			)
		)
		(property "Val" "10k"
			(at 157.48 170.18 90)
			(effects
				(font
					(size 1.27 1.27)
					(thickness 0.15)
				)
				(justify right)
			)
		)
		(property "License" "Apache-2.0"
			(at 181.61 151.13 0)
			(effects
				(font
					(size 1.27 1.27)
					(thickness 0.15)
				)
				(justify left bottom)
				(hide yes)
			)
		)
		(property "Author" "Antmicro"
			(at 184.15 151.13 0)
			(effects
				(font
					(size 1.27 1.27)
					(thickness 0.15)
				)
				(justify left bottom)
				(hide yes)
			)
		)
		(property "Tolerance" "1%"
			(at 166.37 151.13 0)
			(effects
				(font
					(size 1.27 1.27)
				)
				(justify left bottom)
				(hide yes)
			)
		)
		(pin "1"
		)
		(pin "2"
		)
		(instances
			(project "jetson-orin-baseboard"
				(path ""
					(reference "R188")
					(unit 1)
				)
			)
		)
	)
	(symbol
		(lib_id "antmicroTransistorsFETsMOSFETsSingle:PJE138K")
		(at 144.78 64.77 0)
		(unit 1)
		(exclude_from_sim no)
		(in_bom yes)
		(on_board yes)
		(dnp no)
		(property "Reference" "Q11"
			(at 153.67 60.96 0)
			(effects
				(font
					(size 1.27 1.27)
					(thickness 0.15)
				)
				(justify left)
			)
		)
		(property "Value" "PJE138K"
			(at 167.64 73.66 0)
			(effects
				(font
					(size 1.27 1.27)
					(thickness 0.15)
				)
				(justify left bottom)
				(hide yes)
			)
		)
		(property "Footprint" "antmicro-footprints:SOT-523"
			(at 167.64 76.2 0)
			(effects
				(font
					(size 1.27 1.27)
					(thickness 0.15)
				)
				(justify left bottom)
				(hide yes)
			)
		)
		(property "Datasheet" "https://www.mouser.com/datasheet/2/1057/PJE138K-1876698.pdf"
			(at 167.64 78.74 0)
			(effects
				(font
					(size 1.27 1.27)
					(thickness 0.15)
				)
				(justify left bottom)
				(hide yes)
			)
		)
		(property "Description" ""
			(at 144.78 64.77 0)
			(effects
				(font
					(size 1.27 1.27)
				)
				(hide yes)
			)
		)
		(property "MPN" "PJE138K_R1_00001"
			(at 153.67 63.5 0)
			(effects
				(font
					(size 1.27 1.27)
					(thickness 0.15)
				)
				(justify left)
			)
		)
		(property "Manufacturer" "PANJIT"
			(at 167.64 83.82 0)
			(effects
				(font
					(size 1.27 1.27)
					(thickness 0.15)
				)
				(justify left bottom)
				(hide yes)
			)
		)
		(property "Author" "Antmicro"
			(at 167.64 86.36 0)
			(effects
				(font
					(size 1.27 1.27)
					(thickness 0.15)
				)
				(justify left bottom)
				(hide yes)
			)
		)
		(property "License" "Apache-2.0"
			(at 167.64 88.9 0)
			(effects
				(font
					(size 1.27 1.27)
					(thickness 0.15)
				)
				(justify left bottom)
				(hide yes)
			)
		)
		(pin "2"
		)
		(pin "3"
		)
		(pin "1"
		)
		(instances
			(project "jetson-orin-baseboard"
				(path ""
					(reference "Q11")
					(unit 1)
				)
			)
		)
	)
	(symbol
		(lib_id "antmicropower:GND")
		(at 35.56 81.28 0)
		(unit 1)
		(exclude_from_sim no)
		(in_bom yes)
		(on_board yes)
		(dnp no)
		(property "Reference" "#PWR0175"
			(at 35.56 87.63 0)
			(effects
				(font
					(size 1.27 1.27)
				)
				(justify left bottom)
				(hide yes)
			)
		)
		(property "Value" "GND"
			(at 35.56 85.09 0)
			(effects
				(font
					(size 1.27 1.27)
					(thickness 0.15)
				)
			)
		)
		(property "Footprint" ""
			(at 44.45 88.9 0)
			(effects
				(font
					(size 1.27 1.27)
					(thickness 0.15)
				)
				(justify left bottom)
				(hide yes)
			)
		)
		(property "Datasheet" ""
			(at 44.45 93.98 0)
			(effects
				(font
					(size 1.27 1.27)
					(thickness 0.15)
				)
				(justify left bottom)
				(hide yes)
			)
		)
		(property "Description" ""
			(at 35.56 81.28 0)
			(effects
				(font
					(size 1.27 1.27)
				)
				(hide yes)
			)
		)
		(property "Author" "Antmicro"
			(at 44.45 88.9 0)
			(effects
				(font
					(size 1.27 1.27)
					(thickness 0.15)
				)
				(justify left bottom)
				(hide yes)
			)
		)
		(property "License" "Apache-2.0"
			(at 44.45 91.44 0)
			(effects
				(font
					(size 1.27 1.27)
					(thickness 0.15)
				)
				(justify left bottom)
				(hide yes)
			)
		)
		(pin "1"
		)
		(instances
			(project "jetson-orin-baseboard"
				(path ""
					(reference "#PWR0175")
					(unit 1)
				)
			)
		)
	)
	(symbol
		(lib_id "antmicropower:GND")
		(at 36.83 46.99 0)
		(unit 1)
		(exclude_from_sim no)
		(in_bom yes)
		(on_board yes)
		(dnp no)
		(property "Reference" "#PWR0174"
			(at 36.83 53.34 0)
			(effects
				(font
					(size 1.27 1.27)
				)
				(justify left bottom)
				(hide yes)
			)
		)
		(property "Value" "GND"
			(at 36.83 50.8 0)
			(effects
				(font
					(size 1.27 1.27)
					(thickness 0.15)
				)
			)
		)
		(property "Footprint" ""
			(at 45.72 54.61 0)
			(effects
				(font
					(size 1.27 1.27)
					(thickness 0.15)
				)
				(justify left bottom)
				(hide yes)
			)
		)
		(property "Datasheet" ""
			(at 45.72 59.69 0)
			(effects
				(font
					(size 1.27 1.27)
					(thickness 0.15)
				)
				(justify left bottom)
				(hide yes)
			)
		)
		(property "Description" ""
			(at 36.83 46.99 0)
			(effects
				(font
					(size 1.27 1.27)
				)
				(hide yes)
			)
		)
		(property "Author" "Antmicro"
			(at 45.72 54.61 0)
			(effects
				(font
					(size 1.27 1.27)
					(thickness 0.15)
				)
				(justify left bottom)
				(hide yes)
			)
		)
		(property "License" "Apache-2.0"
			(at 45.72 57.15 0)
			(effects
				(font
					(size 1.27 1.27)
					(thickness 0.15)
				)
				(justify left bottom)
				(hide yes)
			)
		)
		(pin "1"
		)
		(instances
			(project "jetson-orin-baseboard"
				(path ""
					(reference "#PWR0174")
					(unit 1)
				)
			)
		)
	)
	(symbol
		(lib_id "antmicropower:VCC")
		(at 223.52 105.41 0)
		(unit 1)
		(exclude_from_sim no)
		(in_bom yes)
		(on_board yes)
		(dnp no)
		(property "Reference" "#PWR0347"
			(at 223.52 109.22 0)
			(effects
				(font
					(size 1.27 1.27)
				)
				(justify left bottom)
				(hide yes)
			)
		)
		(property "Value" "VCC"
			(at 221.615 101.6 0)
			(effects
				(font
					(size 1.27 1.27)
				)
				(justify left)
			)
		)
		(property "Footprint" ""
			(at 223.52 105.41 0)
			(effects
				(font
					(size 1.27 1.27)
				)
				(hide yes)
			)
		)
		(property "Datasheet" ""
			(at 223.52 105.41 0)
			(effects
				(font
					(size 1.27 1.27)
				)
				(hide yes)
			)
		)
		(property "Description" ""
			(at 223.52 105.41 0)
			(effects
				(font
					(size 1.27 1.27)
				)
				(hide yes)
			)
		)
		(pin "1"
		)
		(instances
			(project "jetson-orin-baseboard"
				(path ""
					(reference "#PWR0347")
					(unit 1)
				)
			)
		)
	)
	(symbol
		(lib_id "antmicroPMICVoltageRegulatorsLinear:NCP730BMT330_WSON")
		(at 331.47 30.48 0)
		(unit 1)
		(exclude_from_sim no)
		(in_bom yes)
		(on_board yes)
		(dnp no)
		(property "Reference" "U41"
			(at 339.09 24.13 0)
			(effects
				(font
					(size 1.27 1.27)
				)
			)
		)
		(property "Value" "NCP730BMT330_WSON"
			(at 361.95 35.56 0)
			(effects
				(font
					(size 1.27 1.27)
					(thickness 0.15)
				)
				(justify left bottom)
				(hide yes)
			)
		)
		(property "Footprint" "antmicro-footprints:WSON-6-1EP_2x2mm_P0.65mm"
			(at 361.95 38.1 0)
			(effects
				(font
					(size 1.27 1.27)
					(thickness 0.15)
				)
				(justify left bottom)
				(hide yes)
			)
		)
		(property "Datasheet" "https://www.onsemi.com/download/data-sheet/pdf/ncp730-d.pdf"
			(at 361.95 40.64 0)
			(effects
				(font
					(size 1.27 1.27)
					(thickness 0.15)
				)
				(justify left bottom)
				(hide yes)
			)
		)
		(property "Description" ""
			(at 331.47 30.48 0)
			(effects
				(font
					(size 1.27 1.27)
				)
				(hide yes)
			)
		)
		(property "MPN" "NCP730BMT330TBG"
			(at 339.09 26.67 0)
			(effects
				(font
					(size 1.27 1.27)
					(thickness 0.15)
				)
			)
		)
		(property "Manufacturer" "ON Semiconductor"
			(at 361.95 45.72 0)
			(effects
				(font
					(size 1.27 1.27)
					(thickness 0.15)
				)
				(justify left bottom)
				(hide yes)
			)
		)
		(property "Author" "Antmicro"
			(at 361.95 48.26 0)
			(effects
				(font
					(size 1.27 1.27)
					(thickness 0.15)
				)
				(justify left bottom)
				(hide yes)
			)
		)
		(property "License" "Apache-2.0"
			(at 361.95 50.8 0)
			(effects
				(font
					(size 1.27 1.27)
					(thickness 0.15)
				)
				(justify left bottom)
				(hide yes)
			)
		)
		(pin "1"
		)
		(pin "2"
		)
		(pin "3"
		)
		(pin "4"
		)
		(pin "5"
		)
		(pin "6"
		)
		(pin "7"
		)
		(instances
			(project "jetson-orin-baseboard"
				(path ""
					(reference "U41")
					(unit 1)
				)
			)
		)
	)
	(symbol
		(lib_id "antmicroCapacitors0603:C_22u_16V_0603")
		(at 313.69 148.59 90)
		(unit 1)
		(exclude_from_sim no)
		(in_bom yes)
		(on_board yes)
		(dnp no)
		(property "Reference" "C103"
			(at 314.325 144.145 90)
			(effects
				(font
					(size 1.27 1.27)
				)
				(justify right)
			)
		)
		(property "Value" "C_22u_16V_0603"
			(at 323.85 128.27 0)
			(effects
				(font
					(size 1.27 1.27)
					(thickness 0.15)
				)
				(justify left bottom)
				(hide yes)
			)
		)
		(property "Footprint" "antmicro-footprints:C_0603_1608Metric_EIA"
			(at 326.39 128.27 0)
			(effects
				(font
					(size 1.27 1.27)
					(thickness 0.15)
				)
				(justify left bottom)
				(hide yes)
			)
		)
		(property "Datasheet" "https://product.samsungsem.com/mlcc/CL10A226MO7JZN.do"
			(at 328.93 128.27 0)
			(effects
				(font
					(size 1.27 1.27)
					(thickness 0.15)
				)
				(justify left bottom)
				(hide yes)
			)
		)
		(property "Description" "SMD Multilayer Ceramic Capacitor"
			(at 313.69 148.59 0)
			(effects
				(font
					(size 1.27 1.27)
				)
				(hide yes)
			)
		)
		(property "Manufacturer" "Samsung Electro-Mechanics"
			(at 334.01 128.27 0)
			(effects
				(font
					(size 1.27 1.27)
					(thickness 0.15)
				)
				(justify left bottom)
				(hide yes)
			)
		)
		(property "MPN" "CL10A226MO7JZNC"
			(at 331.47 128.27 0)
			(effects
				(font
					(size 1.27 1.27)
					(thickness 0.15)
				)
				(justify left bottom)
				(hide yes)
			)
		)
		(property "Val" "22u"
			(at 314.325 147.955 90)
			(effects
				(font
					(size 1.27 1.27)
					(thickness 0.15)
				)
				(justify right)
			)
		)
		(property "License" "Apache-2.0"
			(at 336.55 128.27 0)
			(effects
				(font
					(size 1.27 1.27)
					(thickness 0.15)
				)
				(justify left bottom)
				(hide yes)
			)
		)
		(property "Author" "Antmicro"
			(at 339.09 128.27 0)
			(effects
				(font
					(size 1.27 1.27)
					(thickness 0.15)
				)
				(justify left bottom)
				(hide yes)
			)
		)
		(property "Voltage" "16V"
			(at 341.63 128.27 0)
			(effects
				(font
					(size 1.27 1.27)
				)
				(justify left bottom)
				(hide yes)
			)
		)
		(property "Dielectric" ""
			(at 344.17 128.27 0)
			(effects
				(font
					(size 1.27 1.27)
				)
				(justify left bottom)
				(hide yes)
			)
		)
		(pin "1"
		)
		(pin "2"
		)
		(instances
			(project "jetson-orin-baseboard"
				(path ""
					(reference "C103")
					(unit 1)
				)
			)
		)
	)
	(symbol
		(lib_id "antmicroCapacitors0402:C_100n_0402")
		(at 124.46 33.02 90)
		(unit 1)
		(exclude_from_sim no)
		(in_bom yes)
		(on_board yes)
		(dnp no)
		(property "Reference" "C118"
			(at 126.365 29.21 90)
			(effects
				(font
					(size 1.27 1.27)
				)
				(justify right)
			)
		)
		(property "Value" "C_100n_0402"
			(at 134.62 12.7 0)
			(effects
				(font
					(size 1.27 1.27)
					(thickness 0.15)
				)
				(justify left bottom)
				(hide yes)
			)
		)
		(property "Footprint" "antmicro-footprints:C_0402_1005Metric"
			(at 137.16 12.7 0)
			(effects
				(font
					(size 1.27 1.27)
					(thickness 0.15)
				)
				(justify left bottom)
				(hide yes)
			)
		)
		(property "Datasheet" "https://www.murata.com/products/productdetail?partno=GRM155R61H104KE14%23"
			(at 139.7 12.7 0)
			(effects
				(font
					(size 1.27 1.27)
					(thickness 0.15)
				)
				(justify left bottom)
				(hide yes)
			)
		)
		(property "Description" ""
			(at 124.46 33.02 0)
			(effects
				(font
					(size 1.27 1.27)
				)
				(hide yes)
			)
		)
		(property "Manufacturer" "Murata"
			(at 144.78 12.7 0)
			(effects
				(font
					(size 1.27 1.27)
					(thickness 0.15)
				)
				(justify left bottom)
				(hide yes)
			)
		)
		(property "MPN" "GRM155R61H104KE14D"
			(at 142.24 12.7 0)
			(effects
				(font
					(size 1.27 1.27)
					(thickness 0.15)
				)
				(justify left bottom)
				(hide yes)
			)
		)
		(property "Val" "100n"
			(at 126.365 31.75 90)
			(effects
				(font
					(size 1.27 1.27)
					(thickness 0.15)
				)
				(justify right)
			)
		)
		(property "License" "Apache-2.0"
			(at 147.32 12.7 0)
			(effects
				(font
					(size 1.27 1.27)
					(thickness 0.15)
				)
				(justify left bottom)
				(hide yes)
			)
		)
		(property "Author" "Antmicro"
			(at 149.86 12.7 0)
			(effects
				(font
					(size 1.27 1.27)
					(thickness 0.15)
				)
				(justify left bottom)
				(hide yes)
			)
		)
		(property "Voltage" "50V"
			(at 152.4 12.7 0)
			(effects
				(font
					(size 1.27 1.27)
				)
				(justify left bottom)
				(hide yes)
			)
		)
		(property "Dielectric" "X5R"
			(at 154.94 12.7 0)
			(effects
				(font
					(size 1.27 1.27)
				)
				(justify left bottom)
				(hide yes)
			)
		)
		(pin "1"
		)
		(pin "2"
		)
		(instances
			(project "jetson-orin-baseboard"
				(path ""
					(reference "C118")
					(unit 1)
				)
			)
		)
	)
	(symbol
		(lib_id "antmicroPushbuttonSwitches:SW_KMR211NGLFS_SMD")
		(at 43.18 34.29 270)
		(unit 1)
		(exclude_from_sim no)
		(in_bom yes)
		(on_board yes)
		(dnp no)
		(property "Reference" "S4"
			(at 46.355 38.1 90)
			(effects
				(font
					(size 1.27 1.27)
				)
				(justify left)
			)
		)
		(property "Value" "SW_KMR211NGLFS_SMD"
			(at 35.56 59.69 0)
			(effects
				(font
					(size 1.27 1.27)
					(thickness 0.15)
				)
				(justify left bottom)
				(hide yes)
			)
		)
		(property "Footprint" "antmicro-footprints:SW_KMR211NGLFS_SMD"
			(at 33.02 59.69 0)
			(effects
				(font
					(size 1.27 1.27)
					(thickness 0.15)
				)
				(justify left bottom)
				(hide yes)
			)
		)
		(property "Datasheet" "http://www.farnell.com/datasheets/2631211.pdf"
			(at 30.48 59.69 0)
			(effects
				(font
					(size 1.27 1.27)
					(thickness 0.15)
				)
				(justify left bottom)
				(hide yes)
			)
		)
		(property "Description" ""
			(at 43.18 34.29 0)
			(effects
				(font
					(size 1.27 1.27)
				)
				(hide yes)
			)
		)
		(property "MPN" "KMR211NGLFS"
			(at 46.355 40.64 90)
			(effects
				(font
					(size 1.27 1.27)
					(thickness 0.15)
				)
				(justify left)
			)
		)
		(property "Manufacturer" "C&K"
			(at 27.94 59.69 0)
			(effects
				(font
					(size 1.27 1.27)
					(thickness 0.15)
				)
				(justify left bottom)
				(hide yes)
			)
		)
		(property "Author" "Antmicro"
			(at 25.4 59.69 0)
			(effects
				(font
					(size 1.27 1.27)
					(thickness 0.15)
				)
				(justify left bottom)
				(hide yes)
			)
		)
		(property "License" "Apache-2.0"
			(at 22.86 59.69 0)
			(effects
				(font
					(size 1.27 1.27)
					(thickness 0.15)
				)
				(justify left bottom)
				(hide yes)
			)
		)
		(pin "1"
		)
		(pin "2"
		)
		(pin "3"
		)
		(pin "4"
		)
		(instances
			(project "jetson-orin-baseboard"
				(path ""
					(reference "S4")
					(unit 1)
				)
			)
		)
	)
	(symbol
		(lib_id "antmicropower:GND")
		(at 330.2 38.1 0)
		(unit 1)
		(exclude_from_sim no)
		(in_bom yes)
		(on_board yes)
		(dnp no)
		(property "Reference" "#PWR058"
			(at 330.2 44.45 0)
			(effects
				(font
					(size 1.27 1.27)
				)
				(justify left bottom)
				(hide yes)
			)
		)
		(property "Value" "GND"
			(at 330.2 41.91 0)
			(effects
				(font
					(size 1.27 1.27)
					(thickness 0.15)
				)
			)
		)
		(property "Footprint" ""
			(at 339.09 45.72 0)
			(effects
				(font
					(size 1.27 1.27)
					(thickness 0.15)
				)
				(justify left bottom)
				(hide yes)
			)
		)
		(property "Datasheet" ""
			(at 339.09 50.8 0)
			(effects
				(font
					(size 1.27 1.27)
					(thickness 0.15)
				)
				(justify left bottom)
				(hide yes)
			)
		)
		(property "Description" ""
			(at 330.2 38.1 0)
			(effects
				(font
					(size 1.27 1.27)
				)
				(hide yes)
			)
		)
		(property "Author" "Antmicro"
			(at 339.09 45.72 0)
			(effects
				(font
					(size 1.27 1.27)
					(thickness 0.15)
				)
				(justify left bottom)
				(hide yes)
			)
		)
		(property "License" "Apache-2.0"
			(at 339.09 48.26 0)
			(effects
				(font
					(size 1.27 1.27)
					(thickness 0.15)
				)
				(justify left bottom)
				(hide yes)
			)
		)
		(pin "1"
		)
		(instances
			(project "jetson-orin-baseboard"
				(path ""
					(reference "#PWR058")
					(unit 1)
				)
			)
		)
	)
	(symbol
		(lib_id "antmicropower:GND")
		(at 207.01 213.36 0)
		(unit 1)
		(exclude_from_sim no)
		(in_bom yes)
		(on_board yes)
		(dnp no)
		(property "Reference" "#PWR0333"
			(at 207.01 219.71 0)
			(effects
				(font
					(size 1.27 1.27)
				)
				(justify left bottom)
				(hide yes)
			)
		)
		(property "Value" "GND"
			(at 207.01 217.17 0)
			(effects
				(font
					(size 1.27 1.27)
					(thickness 0.15)
				)
			)
		)
		(property "Footprint" ""
			(at 215.9 220.98 0)
			(effects
				(font
					(size 1.27 1.27)
					(thickness 0.15)
				)
				(justify left bottom)
				(hide yes)
			)
		)
		(property "Datasheet" ""
			(at 215.9 226.06 0)
			(effects
				(font
					(size 1.27 1.27)
					(thickness 0.15)
				)
				(justify left bottom)
				(hide yes)
			)
		)
		(property "Description" ""
			(at 207.01 213.36 0)
			(effects
				(font
					(size 1.27 1.27)
				)
				(hide yes)
			)
		)
		(property "Author" "Antmicro"
			(at 215.9 220.98 0)
			(effects
				(font
					(size 1.27 1.27)
					(thickness 0.15)
				)
				(justify left bottom)
				(hide yes)
			)
		)
		(property "License" "Apache-2.0"
			(at 215.9 223.52 0)
			(effects
				(font
					(size 1.27 1.27)
					(thickness 0.15)
				)
				(justify left bottom)
				(hide yes)
			)
		)
		(pin "1"
		)
		(instances
			(project "jetson-orin-baseboard"
				(path ""
					(reference "#PWR0333")
					(unit 1)
				)
			)
		)
	)
	(symbol
		(lib_id "antmicroCapacitors0603:C_22u_16V_0603")
		(at 321.31 148.59 90)
		(unit 1)
		(exclude_from_sim no)
		(in_bom yes)
		(on_board yes)
		(dnp no)
		(property "Reference" "C120"
			(at 321.945 144.145 90)
			(effects
				(font
					(size 1.27 1.27)
				)
				(justify right)
			)
		)
		(property "Value" "C_22u_16V_0603"
			(at 331.47 128.27 0)
			(effects
				(font
					(size 1.27 1.27)
					(thickness 0.15)
				)
				(justify left bottom)
				(hide yes)
			)
		)
		(property "Footprint" "antmicro-footprints:C_0603_1608Metric_EIA"
			(at 334.01 128.27 0)
			(effects
				(font
					(size 1.27 1.27)
					(thickness 0.15)
				)
				(justify left bottom)
				(hide yes)
			)
		)
		(property "Datasheet" "https://product.samsungsem.com/mlcc/CL10A226MO7JZN.do"
			(at 336.55 128.27 0)
			(effects
				(font
					(size 1.27 1.27)
					(thickness 0.15)
				)
				(justify left bottom)
				(hide yes)
			)
		)
		(property "Description" "SMD Multilayer Ceramic Capacitor"
			(at 321.31 148.59 0)
			(effects
				(font
					(size 1.27 1.27)
				)
				(hide yes)
			)
		)
		(property "Manufacturer" "Samsung Electro-Mechanics"
			(at 341.63 128.27 0)
			(effects
				(font
					(size 1.27 1.27)
					(thickness 0.15)
				)
				(justify left bottom)
				(hide yes)
			)
		)
		(property "MPN" "CL10A226MO7JZNC"
			(at 339.09 128.27 0)
			(effects
				(font
					(size 1.27 1.27)
					(thickness 0.15)
				)
				(justify left bottom)
				(hide yes)
			)
		)
		(property "Val" "22u"
			(at 321.945 147.955 90)
			(effects
				(font
					(size 1.27 1.27)
					(thickness 0.15)
				)
				(justify right)
			)
		)
		(property "License" "Apache-2.0"
			(at 344.17 128.27 0)
			(effects
				(font
					(size 1.27 1.27)
					(thickness 0.15)
				)
				(justify left bottom)
				(hide yes)
			)
		)
		(property "Author" "Antmicro"
			(at 346.71 128.27 0)
			(effects
				(font
					(size 1.27 1.27)
					(thickness 0.15)
				)
				(justify left bottom)
				(hide yes)
			)
		)
		(property "Voltage" "16V"
			(at 349.25 128.27 0)
			(effects
				(font
					(size 1.27 1.27)
				)
				(justify left bottom)
				(hide yes)
			)
		)
		(property "Dielectric" ""
			(at 351.79 128.27 0)
			(effects
				(font
					(size 1.27 1.27)
				)
				(justify left bottom)
				(hide yes)
			)
		)
		(pin "1"
		)
		(pin "2"
		)
		(instances
			(project "jetson-orin-baseboard"
				(path ""
					(reference "C120")
					(unit 1)
				)
			)
		)
	)
	(symbol
		(lib_id "antmicroResistors0402:R_560R_0402")
		(at 241.3 251.46 90)
		(unit 1)
		(exclude_from_sim no)
		(in_bom yes)
		(on_board yes)
		(dnp no)
		(property "Reference" "R284"
			(at 242.57 247.65 90)
			(effects
				(font
					(size 1.27 1.27)
					(thickness 0.15)
				)
				(justify right)
			)
		)
		(property "Value" "R_560R_0402"
			(at 254 231.14 0)
			(effects
				(font
					(size 1.27 1.27)
					(thickness 0.15)
				)
				(justify left bottom)
				(hide yes)
			)
		)
		(property "Footprint" "antmicro-footprints:R_0402_1005Metric"
			(at 256.54 231.14 0)
			(effects
				(font
					(size 1.27 1.27)
					(thickness 0.15)
				)
				(justify left bottom)
				(hide yes)
			)
		)
		(property "Datasheet" "https://www.bourns.com/docs/product-datasheets/cr.pdf"
			(at 259.08 231.14 0)
			(effects
				(font
					(size 1.27 1.27)
					(thickness 0.15)
				)
				(justify left bottom)
				(hide yes)
			)
		)
		(property "Description" "SMD Chip Resistor, 560 ohm, ± 1%, 100 mW, 0402 [1005 Metric], Thick Film, Precision"
			(at 241.3 251.46 0)
			(effects
				(font
					(size 1.27 1.27)
				)
				(hide yes)
			)
		)
		(property "MPN" "CR0402-FX-5600GLF"
			(at 261.62 231.14 0)
			(effects
				(font
					(size 1.27 1.27)
					(thickness 0.15)
				)
				(justify left bottom)
				(hide yes)
			)
		)
		(property "Manufacturer" "Bourns"
			(at 264.16 231.14 0)
			(effects
				(font
					(size 1.27 1.27)
					(thickness 0.15)
				)
				(justify left bottom)
				(hide yes)
			)
		)
		(property "License" "Apache-2.0"
			(at 266.7 231.14 0)
			(effects
				(font
					(size 1.27 1.27)
					(thickness 0.15)
				)
				(justify left bottom)
				(hide yes)
			)
		)
		(property "Author" "Antmicro"
			(at 269.24 231.14 0)
			(effects
				(font
					(size 1.27 1.27)
					(thickness 0.15)
				)
				(justify left bottom)
				(hide yes)
			)
		)
		(property "Val" "560R"
			(at 242.57 250.19 90)
			(effects
				(font
					(size 1.27 1.27)
					(thickness 0.15)
				)
				(justify right)
			)
		)
		(property "Tolerance" "1%"
			(at 251.46 231.14 0)
			(effects
				(font
					(size 1.27 1.27)
				)
				(justify left bottom)
				(hide yes)
			)
		)
		(pin "1"
		)
		(pin "2"
		)
		(instances
			(project "jetson-orin-baseboard"
				(path ""
					(reference "R284")
					(unit 1)
				)
			)
		)
	)
	(symbol
		(lib_id "antmicroLEDIndicationDiscrete:LED_G_0603_LTST-C190GKT")
		(at 156.21 177.8 90)
		(unit 1)
		(exclude_from_sim no)
		(in_bom yes)
		(on_board yes)
		(dnp no)
		(property "Reference" "D53"
			(at 157.48 173.99 90)
			(effects
				(font
					(size 1.27 1.27)
				)
				(justify right)
			)
		)
		(property "Value" "LED_G_0603_LTST-C190GKT"
			(at 163.83 154.94 0)
			(effects
				(font
					(size 1.27 1.27)
					(thickness 0.15)
				)
				(justify left bottom)
				(hide yes)
			)
		)
		(property "Footprint" "antmicro-footprints:LED_0603_1608Metric_G"
			(at 166.37 154.94 0)
			(effects
				(font
					(size 1.27 1.27)
					(thickness 0.15)
				)
				(justify left bottom)
				(hide yes)
			)
		)
		(property "Datasheet" "https://media.digikey.com/pdf/Data%20Sheets/Lite-On%20PDFs/LTST-C190GKT.pdf"
			(at 168.91 154.94 0)
			(effects
				(font
					(size 1.27 1.27)
					(thickness 0.15)
				)
				(justify left bottom)
				(hide yes)
			)
		)
		(property "Description" ""
			(at 156.21 177.8 0)
			(effects
				(font
					(size 1.27 1.27)
				)
				(hide yes)
			)
		)
		(property "MPN" "LTST-C190GKT"
			(at 171.45 154.94 0)
			(effects
				(font
					(size 1.27 1.27)
					(thickness 0.15)
				)
				(justify left bottom)
				(hide yes)
			)
		)
		(property "Manufacturer" "Lite-On"
			(at 173.99 154.94 0)
			(effects
				(font
					(size 1.27 1.27)
					(thickness 0.15)
				)
				(justify left bottom)
				(hide yes)
			)
		)
		(property "Author" "Antmicro"
			(at 176.53 154.94 0)
			(effects
				(font
					(size 1.27 1.27)
					(thickness 0.15)
				)
				(justify left bottom)
				(hide yes)
			)
		)
		(property "License" "Apache-2.0"
			(at 179.07 154.94 0)
			(effects
				(font
					(size 1.27 1.27)
					(thickness 0.15)
				)
				(justify left bottom)
				(hide yes)
			)
		)
		(property "Color" "Green"
			(at 157.48 176.53 90)
			(effects
				(font
					(size 1.27 1.27)
				)
				(justify right)
			)
		)
		(pin "1"
		)
		(pin "2"
		)
		(instances
			(project "jetson-orin-baseboard"
				(path ""
					(reference "D53")
					(unit 1)
				)
			)
		)
	)
	(symbol
		(lib_id "antmicropower:+5V")
		(at 260.35 234.95 0)
		(unit 1)
		(exclude_from_sim no)
		(in_bom yes)
		(on_board yes)
		(dnp no)
		(property "Reference" "#PWR03"
			(at 260.35 238.76 0)
			(effects
				(font
					(size 1.27 1.27)
				)
				(justify left bottom)
				(hide yes)
			)
		)
		(property "Value" "+5V_SoM"
			(at 260.35 231.14 0)
			(effects
				(font
					(size 1.27 1.27)
					(thickness 0.15)
				)
			)
		)
		(property "Footprint" ""
			(at 275.59 242.57 0)
			(effects
				(font
					(size 1.27 1.27)
					(thickness 0.15)
				)
				(justify left bottom)
				(hide yes)
			)
		)
		(property "Datasheet" ""
			(at 275.59 245.11 0)
			(effects
				(font
					(size 1.27 1.27)
					(thickness 0.15)
				)
				(justify left bottom)
				(hide yes)
			)
		)
		(property "Description" ""
			(at 260.35 234.95 0)
			(effects
				(font
					(size 1.27 1.27)
				)
				(hide yes)
			)
		)
		(property "Author" "Antmicro"
			(at 275.59 242.57 0)
			(effects
				(font
					(size 1.27 1.27)
					(thickness 0.15)
				)
				(justify left bottom)
				(hide yes)
			)
		)
		(property "License" "Apache-2.0"
			(at 275.59 245.11 0)
			(effects
				(font
					(size 1.27 1.27)
					(thickness 0.15)
				)
				(justify left bottom)
				(hide yes)
			)
		)
		(pin "1"
		)
		(instances
			(project "jetson-orin-baseboard"
				(path ""
					(reference "#PWR03")
					(unit 1)
				)
			)
		)
	)
	(symbol
		(lib_id "antmicroResistors0402:R_499k_0402")
		(at 214.63 138.43 90)
		(unit 1)
		(exclude_from_sim no)
		(in_bom no)
		(on_board yes)
		(dnp yes)
		(property "Reference" "R159"
			(at 215.9 134.62 90)
			(effects
				(font
					(size 1.27 1.27)
					(thickness 0.15)
				)
				(justify right)
			)
		)
		(property "Value" "R_499k_0402"
			(at 227.33 118.11 0)
			(effects
				(font
					(size 1.27 1.27)
					(thickness 0.15)
				)
				(justify left bottom)
				(hide yes)
			)
		)
		(property "Footprint" "antmicro-footprints:R_0402_1005Metric"
			(at 229.87 118.11 0)
			(effects
				(font
					(size 1.27 1.27)
					(thickness 0.15)
				)
				(justify left bottom)
				(hide yes)
			)
		)
		(property "Datasheet" "https://www.mouser.com/datasheet/2/54/cr-1858361.pdf"
			(at 232.41 118.11 0)
			(effects
				(font
					(size 1.27 1.27)
					(thickness 0.15)
				)
				(justify left bottom)
				(hide yes)
			)
		)
		(property "Description" ""
			(at 214.63 138.43 0)
			(effects
				(font
					(size 1.27 1.27)
				)
				(hide yes)
			)
		)
		(property "MPN" "CR0402-FX-4993GLF"
			(at 234.95 118.11 0)
			(effects
				(font
					(size 1.27 1.27)
					(thickness 0.15)
				)
				(justify left bottom)
				(hide yes)
			)
		)
		(property "Manufacturer" "Bourns"
			(at 237.49 118.11 0)
			(effects
				(font
					(size 1.27 1.27)
					(thickness 0.15)
				)
				(justify left bottom)
				(hide yes)
			)
		)
		(property "License" "Apache-2.0"
			(at 240.03 118.11 0)
			(effects
				(font
					(size 1.27 1.27)
					(thickness 0.15)
				)
				(justify left bottom)
				(hide yes)
			)
		)
		(property "Author" "Antmicro"
			(at 242.57 118.11 0)
			(effects
				(font
					(size 1.27 1.27)
					(thickness 0.15)
				)
				(justify left bottom)
				(hide yes)
			)
		)
		(property "Val" "499k"
			(at 215.9 137.16 90)
			(effects
				(font
					(size 1.27 1.27)
					(thickness 0.15)
				)
				(justify right)
			)
		)
		(property "Tolerance" "1%"
			(at 224.79 118.11 0)
			(effects
				(font
					(size 1.27 1.27)
				)
				(justify left bottom)
				(hide yes)
			)
		)
		(pin "2"
		)
		(pin "1"
		)
		(instances
			(project "jetson-orin-baseboard"
				(path ""
					(reference "R159")
					(unit 1)
				)
			)
		)
	)
	(symbol
		(lib_id "antmicropower:GND")
		(at 236.22 57.15 0)
		(unit 1)
		(exclude_from_sim no)
		(in_bom yes)
		(on_board yes)
		(dnp no)
		(property "Reference" "#PWR0255"
			(at 236.22 63.5 0)
			(effects
				(font
					(size 1.27 1.27)
				)
				(justify left bottom)
				(hide yes)
			)
		)
		(property "Value" "GND"
			(at 236.22 60.96 0)
			(effects
				(font
					(size 1.27 1.27)
					(thickness 0.15)
				)
			)
		)
		(property "Footprint" ""
			(at 245.11 64.77 0)
			(effects
				(font
					(size 1.27 1.27)
					(thickness 0.15)
				)
				(justify left bottom)
				(hide yes)
			)
		)
		(property "Datasheet" ""
			(at 245.11 69.85 0)
			(effects
				(font
					(size 1.27 1.27)
					(thickness 0.15)
				)
				(justify left bottom)
				(hide yes)
			)
		)
		(property "Description" ""
			(at 236.22 57.15 0)
			(effects
				(font
					(size 1.27 1.27)
				)
				(hide yes)
			)
		)
		(property "Author" "Antmicro"
			(at 245.11 64.77 0)
			(effects
				(font
					(size 1.27 1.27)
					(thickness 0.15)
				)
				(justify left bottom)
				(hide yes)
			)
		)
		(property "License" "Apache-2.0"
			(at 245.11 67.31 0)
			(effects
				(font
					(size 1.27 1.27)
					(thickness 0.15)
				)
				(justify left bottom)
				(hide yes)
			)
		)
		(pin "1"
		)
		(instances
			(project "jetson-orin-baseboard"
				(path ""
					(reference "#PWR0255")
					(unit 1)
				)
			)
		)
	)
	(symbol
		(lib_id "antmicropower:VCC")
		(at 189.23 186.69 0)
		(unit 1)
		(exclude_from_sim no)
		(in_bom yes)
		(on_board yes)
		(dnp no)
		(property "Reference" "#PWR0273"
			(at 189.23 190.5 0)
			(effects
				(font
					(size 1.27 1.27)
				)
				(justify left bottom)
				(hide yes)
			)
		)
		(property "Value" "VCC"
			(at 187.325 182.88 0)
			(effects
				(font
					(size 1.27 1.27)
				)
				(justify left)
			)
		)
		(property "Footprint" ""
			(at 189.23 186.69 0)
			(effects
				(font
					(size 1.27 1.27)
				)
				(hide yes)
			)
		)
		(property "Datasheet" ""
			(at 189.23 186.69 0)
			(effects
				(font
					(size 1.27 1.27)
				)
				(hide yes)
			)
		)
		(property "Description" ""
			(at 189.23 186.69 0)
			(effects
				(font
					(size 1.27 1.27)
				)
				(hide yes)
			)
		)
		(pin "1"
		)
		(instances
			(project "jetson-orin-baseboard"
				(path ""
					(reference "#PWR0273")
					(unit 1)
				)
			)
		)
	)
	(symbol
		(lib_id "antmicropower:GND")
		(at 358.14 142.24 0)
		(unit 1)
		(exclude_from_sim no)
		(in_bom yes)
		(on_board yes)
		(dnp no)
		(property "Reference" "#PWR0318"
			(at 358.14 148.59 0)
			(effects
				(font
					(size 1.27 1.27)
				)
				(justify left bottom)
				(hide yes)
			)
		)
		(property "Value" "GND"
			(at 358.14 146.05 0)
			(effects
				(font
					(size 1.27 1.27)
					(thickness 0.15)
				)
			)
		)
		(property "Footprint" ""
			(at 367.03 149.86 0)
			(effects
				(font
					(size 1.27 1.27)
					(thickness 0.15)
				)
				(justify left bottom)
				(hide yes)
			)
		)
		(property "Datasheet" ""
			(at 367.03 154.94 0)
			(effects
				(font
					(size 1.27 1.27)
					(thickness 0.15)
				)
				(justify left bottom)
				(hide yes)
			)
		)
		(property "Description" ""
			(at 358.14 142.24 0)
			(effects
				(font
					(size 1.27 1.27)
				)
				(hide yes)
			)
		)
		(property "Author" "Antmicro"
			(at 367.03 149.86 0)
			(effects
				(font
					(size 1.27 1.27)
					(thickness 0.15)
				)
				(justify left bottom)
				(hide yes)
			)
		)
		(property "License" "Apache-2.0"
			(at 367.03 152.4 0)
			(effects
				(font
					(size 1.27 1.27)
					(thickness 0.15)
				)
				(justify left bottom)
				(hide yes)
			)
		)
		(pin "1"
		)
		(instances
			(project "jetson-orin-baseboard"
				(path ""
					(reference "#PWR0318")
					(unit 1)
				)
			)
		)
	)
	(symbol
		(lib_id "antmicroTransistorsFETsMOSFETsSingle:SSM3J332R")
		(at 63.5 125.73 90)
		(unit 1)
		(exclude_from_sim no)
		(in_bom yes)
		(on_board yes)
		(dnp no)
		(fields_autoplaced yes)
		(property "Reference" "Q15"
			(at 60.96 111.76 90)
			(effects
				(font
					(size 1.27 1.27)
				)
			)
		)
		(property "Value" "SSM3J332R"
			(at 66.04 111.76 0)
			(effects
				(font
					(size 1.27 1.27)
					(thickness 0.15)
				)
				(justify left bottom)
				(hide yes)
			)
		)
		(property "Footprint" "antmicro-footprints:SOT-23-3"
			(at 68.58 111.76 0)
			(effects
				(font
					(size 1.27 1.27)
					(thickness 0.15)
				)
				(justify left bottom)
				(hide yes)
			)
		)
		(property "Datasheet" "https://www.mouser.com/datasheet/2/408/SSM3J332R_datasheet_en_20181015-1150575.pdf"
			(at 71.12 111.76 0)
			(effects
				(font
					(size 1.27 1.27)
					(thickness 0.15)
				)
				(justify left bottom)
				(hide yes)
			)
		)
		(property "Description" ""
			(at 63.5 125.73 0)
			(effects
				(font
					(size 1.27 1.27)
				)
				(hide yes)
			)
		)
		(property "MPN" "SSM3J332R,LF"
			(at 60.96 114.3 90)
			(effects
				(font
					(size 1.27 1.27)
					(thickness 0.15)
				)
			)
		)
		(property "Manufacturer" "Toshiba"
			(at 76.2 111.76 0)
			(effects
				(font
					(size 1.27 1.27)
					(thickness 0.15)
				)
				(justify left bottom)
				(hide yes)
			)
		)
		(property "Author" "Antmicro"
			(at 78.74 111.76 0)
			(effects
				(font
					(size 1.27 1.27)
					(thickness 0.15)
				)
				(justify left bottom)
				(hide yes)
			)
		)
		(property "License" "Apache-2.0"
			(at 81.28 111.76 0)
			(effects
				(font
					(size 1.27 1.27)
					(thickness 0.15)
				)
				(justify left bottom)
				(hide yes)
			)
		)
		(pin "1"
		)
		(pin "2"
		)
		(pin "3"
		)
		(instances
			(project "jetson-orin-baseboard"
				(path ""
					(reference "Q15")
					(unit 1)
				)
			)
		)
	)
	(symbol
		(lib_id "antmicroResistors0402:R_100k_0402")
		(at 153.67 269.24 270)
		(mirror x)
		(unit 1)
		(exclude_from_sim no)
		(in_bom yes)
		(on_board yes)
		(dnp no)
		(property "Reference" "R285"
			(at 152.4 265.43 90)
			(effects
				(font
					(size 1.27 1.27)
				)
				(justify right)
			)
		)
		(property "Value" "R_100k_0402"
			(at 140.97 248.92 0)
			(effects
				(font
					(size 1.27 1.27)
					(thickness 0.15)
				)
				(justify left bottom)
				(hide yes)
			)
		)
		(property "Footprint" "antmicro-footprints:R_0402_1005Metric"
			(at 138.43 248.92 0)
			(effects
				(font
					(size 1.27 1.27)
					(thickness 0.15)
				)
				(justify left bottom)
				(hide yes)
			)
		)
		(property "Datasheet" "https://www.bourns.com/docs/product-datasheets/cr.pdf"
			(at 135.89 248.92 0)
			(effects
				(font
					(size 1.27 1.27)
					(thickness 0.15)
				)
				(justify left bottom)
				(hide yes)
			)
		)
		(property "Description" ""
			(at 153.67 269.24 0)
			(effects
				(font
					(size 1.27 1.27)
				)
				(hide yes)
			)
		)
		(property "Manufacturer" "Bourns"
			(at 130.81 248.92 0)
			(effects
				(font
					(size 1.27 1.27)
					(thickness 0.15)
				)
				(justify left bottom)
				(hide yes)
			)
		)
		(property "MPN" "CR0402-FX-1003GLF"
			(at 133.35 248.92 0)
			(effects
				(font
					(size 1.27 1.27)
					(thickness 0.15)
				)
				(justify left bottom)
				(hide yes)
			)
		)
		(property "Val" "100k"
			(at 152.4 267.97 90)
			(effects
				(font
					(size 1.27 1.27)
					(thickness 0.15)
				)
				(justify right)
			)
		)
		(property "License" "Apache-2.0"
			(at 128.27 248.92 0)
			(effects
				(font
					(size 1.27 1.27)
					(thickness 0.15)
				)
				(justify left bottom)
				(hide yes)
			)
		)
		(property "Author" "Antmicro"
			(at 125.73 248.92 0)
			(effects
				(font
					(size 1.27 1.27)
					(thickness 0.15)
				)
				(justify left bottom)
				(hide yes)
			)
		)
		(property "Tolerance" "1%"
			(at 143.51 248.92 0)
			(effects
				(font
					(size 1.27 1.27)
				)
				(justify left bottom)
				(hide yes)
			)
		)
		(pin "1"
		)
		(pin "2"
		)
		(instances
			(project "jetson-orin-baseboard"
				(path ""
					(reference "R285")
					(unit 1)
				)
			)
		)
	)
	(symbol
		(lib_id "antmicropower:GND")
		(at 156.21 181.61 0)
		(unit 1)
		(exclude_from_sim no)
		(in_bom yes)
		(on_board yes)
		(dnp no)
		(property "Reference" "#PWR0257"
			(at 156.21 187.96 0)
			(effects
				(font
					(size 1.27 1.27)
				)
				(justify left bottom)
				(hide yes)
			)
		)
		(property "Value" "GND"
			(at 156.21 185.42 0)
			(effects
				(font
					(size 1.27 1.27)
					(thickness 0.15)
				)
			)
		)
		(property "Footprint" ""
			(at 165.1 189.23 0)
			(effects
				(font
					(size 1.27 1.27)
					(thickness 0.15)
				)
				(justify left bottom)
				(hide yes)
			)
		)
		(property "Datasheet" ""
			(at 165.1 194.31 0)
			(effects
				(font
					(size 1.27 1.27)
					(thickness 0.15)
				)
				(justify left bottom)
				(hide yes)
			)
		)
		(property "Description" ""
			(at 156.21 181.61 0)
			(effects
				(font
					(size 1.27 1.27)
				)
				(hide yes)
			)
		)
		(property "Author" "Antmicro"
			(at 165.1 189.23 0)
			(effects
				(font
					(size 1.27 1.27)
					(thickness 0.15)
				)
				(justify left bottom)
				(hide yes)
			)
		)
		(property "License" "Apache-2.0"
			(at 165.1 191.77 0)
			(effects
				(font
					(size 1.27 1.27)
					(thickness 0.15)
				)
				(justify left bottom)
				(hide yes)
			)
		)
		(pin "1"
		)
		(instances
			(project "jetson-orin-baseboard"
				(path ""
					(reference "#PWR0257")
					(unit 1)
				)
			)
		)
	)
	(symbol
		(lib_id "antmicroResistors0402:R_200k_0402")
		(at 91.44 59.69 0)
		(unit 1)
		(exclude_from_sim no)
		(in_bom yes)
		(on_board yes)
		(dnp no)
		(property "Reference" "R257"
			(at 96.52 59.055 0)
			(effects
				(font
					(size 1.27 1.27)
				)
				(justify left bottom)
			)
		)
		(property "Value" "R_200k_0402"
			(at 111.76 72.39 0)
			(effects
				(font
					(size 1.27 1.27)
					(thickness 0.15)
				)
				(justify left bottom)
				(hide yes)
			)
		)
		(property "Footprint" "antmicro-footprints:R_0402_1005Metric"
			(at 111.76 74.93 0)
			(effects
				(font
					(size 1.27 1.27)
					(thickness 0.15)
				)
				(justify left bottom)
				(hide yes)
			)
		)
		(property "Datasheet" "https://www.bourns.com/docs/product-datasheets/cr.pdf"
			(at 111.76 77.47 0)
			(effects
				(font
					(size 1.27 1.27)
					(thickness 0.15)
				)
				(justify left bottom)
				(hide yes)
			)
		)
		(property "Description" ""
			(at 91.44 59.69 0)
			(effects
				(font
					(size 1.27 1.27)
				)
				(hide yes)
			)
		)
		(property "Manufacturer" "Bourns"
			(at 111.76 82.55 0)
			(effects
				(font
					(size 1.27 1.27)
					(thickness 0.15)
				)
				(justify left bottom)
				(hide yes)
			)
		)
		(property "MPN" "CR0402-FX-2003GLF"
			(at 111.76 80.01 0)
			(effects
				(font
					(size 1.27 1.27)
					(thickness 0.15)
				)
				(justify left bottom)
				(hide yes)
			)
		)
		(property "Val" "200k"
			(at 86.995 59.055 0)
			(effects
				(font
					(size 1.27 1.27)
					(thickness 0.15)
				)
				(justify left bottom)
			)
		)
		(property "License" "Apache-2.0"
			(at 111.76 85.09 0)
			(effects
				(font
					(size 1.27 1.27)
					(thickness 0.15)
				)
				(justify left bottom)
				(hide yes)
			)
		)
		(property "Author" "Antmicro"
			(at 111.76 87.63 0)
			(effects
				(font
					(size 1.27 1.27)
					(thickness 0.15)
				)
				(justify left bottom)
				(hide yes)
			)
		)
		(property "Tolerance" "1%"
			(at 111.76 69.85 0)
			(effects
				(font
					(size 1.27 1.27)
				)
				(justify left bottom)
				(hide yes)
			)
		)
		(pin "1"
		)
		(pin "2"
		)
		(instances
			(project "jetson-orin-baseboard"
				(path ""
					(reference "R257")
					(unit 1)
				)
			)
		)
	)
	(symbol
		(lib_id "antmicroResistors0402:R_470k_0402")
		(at 251.46 271.78 180)
		(unit 1)
		(exclude_from_sim no)
		(in_bom yes)
		(on_board yes)
		(dnp no)
		(property "Reference" "R272"
			(at 253.365 270.51 0)
			(effects
				(font
					(size 1.27 1.27)
					(thickness 0.15)
				)
			)
		)
		(property "Value" "R_470k_0402"
			(at 231.14 259.08 0)
			(effects
				(font
					(size 1.27 1.27)
					(thickness 0.15)
				)
				(justify left bottom)
				(hide yes)
			)
		)
		(property "Footprint" "antmicro-footprints:R_0402_1005Metric"
			(at 231.14 256.54 0)
			(effects
				(font
					(size 1.27 1.27)
					(thickness 0.15)
				)
				(justify left bottom)
				(hide yes)
			)
		)
		(property "Datasheet" "https://www.bourns.com/docs/product-datasheets/cr.pdf"
			(at 231.14 254 0)
			(effects
				(font
					(size 1.27 1.27)
					(thickness 0.15)
				)
				(justify left bottom)
				(hide yes)
			)
		)
		(property "Description" "SMD Chip Resistor, 470 kohm, ± 1%, 62.5 mW, 0402 [1005 Metric], Thick Film, Sulfur Resistant"
			(at 251.46 271.78 0)
			(effects
				(font
					(size 1.27 1.27)
				)
				(hide yes)
			)
		)
		(property "MPN" "CR0402-FX-4703GLF"
			(at 231.14 251.46 0)
			(effects
				(font
					(size 1.27 1.27)
					(thickness 0.15)
				)
				(justify left bottom)
				(hide yes)
			)
		)
		(property "Manufacturer" "Bourns"
			(at 231.14 248.92 0)
			(effects
				(font
					(size 1.27 1.27)
					(thickness 0.15)
				)
				(justify left bottom)
				(hide yes)
			)
		)
		(property "License" "Apache-2.0"
			(at 231.14 246.38 0)
			(effects
				(font
					(size 1.27 1.27)
					(thickness 0.15)
				)
				(justify left bottom)
				(hide yes)
			)
		)
		(property "Author" "Antmicro"
			(at 231.14 243.84 0)
			(effects
				(font
					(size 1.27 1.27)
					(thickness 0.15)
				)
				(justify left bottom)
				(hide yes)
			)
		)
		(property "Val" "470k"
			(at 244.475 270.51 0)
			(effects
				(font
					(size 1.27 1.27)
					(thickness 0.15)
				)
			)
		)
		(property "Tolerance" "1%"
			(at 231.14 261.62 0)
			(effects
				(font
					(size 1.27 1.27)
				)
				(justify left bottom)
				(hide yes)
			)
		)
		(pin "2"
		)
		(pin "1"
		)
		(instances
			(project ""
				(path ""
					(reference "R272")
					(unit 1)
				)
			)
		)
	)
	(symbol
		(lib_id "antmicroLogicBuffersDriversReceiversTransceivers:74LVC2G14_SOT457")
		(at 127 52.07 0)
		(unit 1)
		(exclude_from_sim no)
		(in_bom yes)
		(on_board yes)
		(dnp no)
		(property "Reference" "U37"
			(at 127.635 41.91 0)
			(effects
				(font
					(size 1.27 1.27)
				)
				(justify left)
			)
		)
		(property "Value" "74LVC2G14_SOT457"
			(at 157.48 60.96 0)
			(effects
				(font
					(size 1.27 1.27)
					(thickness 0.15)
				)
				(justify left bottom)
				(hide yes)
			)
		)
		(property "Footprint" "antmicro-footprints:SOT-23-6"
			(at 157.48 63.5 0)
			(effects
				(font
					(size 1.27 1.27)
					(thickness 0.15)
				)
				(justify left bottom)
				(hide yes)
			)
		)
		(property "Datasheet" "https://assets.nexperia.com/documents/data-sheet/74LVC2G14.pdf"
			(at 157.48 66.04 0)
			(effects
				(font
					(size 1.27 1.27)
					(thickness 0.15)
				)
				(justify left bottom)
				(hide yes)
			)
		)
		(property "Description" ""
			(at 127 52.07 0)
			(effects
				(font
					(size 1.27 1.27)
				)
				(hide yes)
			)
		)
		(property "MPN" "74LVC2G14GV,125"
			(at 114.3 43.815 0)
			(effects
				(font
					(size 1.27 1.27)
					(thickness 0.15)
				)
				(justify left)
			)
		)
		(property "Manufacturer" "Nexperia"
			(at 157.48 71.12 0)
			(effects
				(font
					(size 1.27 1.27)
					(thickness 0.15)
				)
				(justify left bottom)
				(hide yes)
			)
		)
		(property "Author" "Antmicro"
			(at 157.48 73.66 0)
			(effects
				(font
					(size 1.27 1.27)
					(thickness 0.15)
				)
				(justify left bottom)
				(hide yes)
			)
		)
		(property "License" "Apache-2.0"
			(at 157.48 76.2 0)
			(effects
				(font
					(size 1.27 1.27)
					(thickness 0.15)
				)
				(justify left bottom)
				(hide yes)
			)
		)
		(pin "1"
		)
		(pin "2"
		)
		(pin "3"
		)
		(pin "4"
		)
		(pin "5"
		)
		(pin "6"
		)
		(instances
			(project "jetson-orin-baseboard"
				(path ""
					(reference "U37")
					(unit 1)
				)
			)
		)
	)
	(symbol
		(lib_id "antmicroResistors0402:R_470R_0402")
		(at 162.56 247.65 90)
		(unit 1)
		(exclude_from_sim no)
		(in_bom yes)
		(on_board yes)
		(dnp no)
		(property "Reference" "R286"
			(at 163.83 243.8399 90)
			(effects
				(font
					(size 1.27 1.27)
				)
				(justify right)
			)
		)
		(property "Value" "R_470R_0402"
			(at 175.26 227.33 0)
			(effects
				(font
					(size 1.27 1.27)
					(thickness 0.15)
				)
				(justify left bottom)
				(hide yes)
			)
		)
		(property "Footprint" "antmicro-footprints:R_0402_1005Metric"
			(at 177.8 227.33 0)
			(effects
				(font
					(size 1.27 1.27)
					(thickness 0.15)
				)
				(justify left bottom)
				(hide yes)
			)
		)
		(property "Datasheet" "https://www.bourns.com/docs/product-datasheets/cr.pdf"
			(at 180.34 227.33 0)
			(effects
				(font
					(size 1.27 1.27)
					(thickness 0.15)
				)
				(justify left bottom)
				(hide yes)
			)
		)
		(property "Description" ""
			(at 162.56 247.65 0)
			(effects
				(font
					(size 1.27 1.27)
				)
				(hide yes)
			)
		)
		(property "Manufacturer" "Bourns"
			(at 185.42 227.33 0)
			(effects
				(font
					(size 1.27 1.27)
					(thickness 0.15)
				)
				(justify left bottom)
				(hide yes)
			)
		)
		(property "MPN" "CR0402-FX-4700GLF"
			(at 182.88 227.33 0)
			(effects
				(font
					(size 1.27 1.27)
					(thickness 0.15)
				)
				(justify left bottom)
				(hide yes)
			)
		)
		(property "Val" "470R"
			(at 163.83 246.38 90)
			(effects
				(font
					(size 1.27 1.27)
					(thickness 0.15)
				)
				(justify right)
			)
		)
		(property "License" "Apache-2.0"
			(at 187.96 227.33 0)
			(effects
				(font
					(size 1.27 1.27)
					(thickness 0.15)
				)
				(justify left bottom)
				(hide yes)
			)
		)
		(property "Author" "Antmicro"
			(at 190.5 227.33 0)
			(effects
				(font
					(size 1.27 1.27)
					(thickness 0.15)
				)
				(justify left bottom)
				(hide yes)
			)
		)
		(property "Tolerance" "1%"
			(at 172.72 227.33 0)
			(effects
				(font
					(size 1.27 1.27)
				)
				(justify left bottom)
				(hide yes)
			)
		)
		(pin "1"
		)
		(pin "2"
		)
		(instances
			(project "jetson-orin-baseboard"
				(path ""
					(reference "R286")
					(unit 1)
				)
			)
		)
	)
	(symbol
		(lib_id "antmicroDiodesRectifiersSingle:RB521S30T1G")
		(at 173.99 74.93 90)
		(unit 1)
		(exclude_from_sim no)
		(in_bom yes)
		(on_board yes)
		(dnp no)
		(property "Reference" "D37"
			(at 174.625 74.93 90)
			(effects
				(font
					(size 1.27 1.27)
				)
				(justify right)
			)
		)
		(property "Value" "RB521S30T1G"
			(at 189.23 52.07 0)
			(effects
				(font
					(size 1.27 1.27)
					(thickness 0.15)
				)
				(justify left bottom)
				(hide yes)
			)
		)
		(property "Footprint" "antmicro-footprints:SOD-523"
			(at 184.15 52.07 0)
			(effects
				(font
					(size 1.27 1.27)
					(thickness 0.15)
				)
				(justify left bottom)
				(hide yes)
			)
		)
		(property "Datasheet" "https://www.onsemi.com/pdf/datasheet/rb521s30t1-d.pdf"
			(at 186.69 52.07 0)
			(effects
				(font
					(size 1.27 1.27)
					(thickness 0.15)
				)
				(justify left bottom)
				(hide yes)
			)
		)
		(property "Description" ""
			(at 173.99 74.93 0)
			(effects
				(font
					(size 1.27 1.27)
				)
				(hide yes)
			)
		)
		(property "MPN" "RB521S30T1G"
			(at 174.625 77.47 90)
			(effects
				(font
					(size 1.27 1.27)
					(thickness 0.15)
				)
				(justify right)
			)
		)
		(property "Manufacturer" "ON Semiconductor"
			(at 191.77 52.07 0)
			(effects
				(font
					(size 1.27 1.27)
					(thickness 0.15)
				)
				(justify left bottom)
				(hide yes)
			)
		)
		(property "Author" "Antmicro"
			(at 194.31 52.07 0)
			(effects
				(font
					(size 1.27 1.27)
					(thickness 0.15)
				)
				(justify left bottom)
				(hide yes)
			)
		)
		(property "License" "Apache-2.0"
			(at 196.85 52.07 0)
			(effects
				(font
					(size 1.27 1.27)
					(thickness 0.15)
				)
				(justify left bottom)
				(hide yes)
			)
		)
		(pin "1"
		)
		(pin "2"
		)
		(instances
			(project "jetson-orin-baseboard"
				(path ""
					(reference "D37")
					(unit 1)
				)
			)
		)
	)
	(symbol
		(lib_id "antmicroResistors0402:R_45k3_0402")
		(at 302.26 199.39 90)
		(unit 1)
		(exclude_from_sim no)
		(in_bom yes)
		(on_board yes)
		(dnp no)
		(property "Reference" "R177"
			(at 303.53 195.58 90)
			(effects
				(font
					(size 1.27 1.27)
					(thickness 0.15)
				)
				(justify right)
			)
		)
		(property "Value" "R_45k3_0402"
			(at 314.96 179.07 0)
			(effects
				(font
					(size 1.27 1.27)
					(thickness 0.15)
				)
				(justify left bottom)
				(hide yes)
			)
		)
		(property "Footprint" "antmicro-footprints:R_0402_1005Metric"
			(at 317.5 179.07 0)
			(effects
				(font
					(size 1.27 1.27)
					(thickness 0.15)
				)
				(justify left bottom)
				(hide yes)
			)
		)
		(property "Datasheet" "https://www.bourns.com/docs/product-datasheets/cr.pdf"
			(at 320.04 179.07 0)
			(effects
				(font
					(size 1.27 1.27)
					(thickness 0.15)
				)
				(justify left bottom)
				(hide yes)
			)
		)
		(property "Description" ""
			(at 302.26 199.39 0)
			(effects
				(font
					(size 1.27 1.27)
				)
				(hide yes)
			)
		)
		(property "MPN" "CR0402-FX-4532GLF"
			(at 322.58 179.07 0)
			(effects
				(font
					(size 1.27 1.27)
					(thickness 0.15)
				)
				(justify left bottom)
				(hide yes)
			)
		)
		(property "Manufacturer" "Bourns"
			(at 325.12 179.07 0)
			(effects
				(font
					(size 1.27 1.27)
					(thickness 0.15)
				)
				(justify left bottom)
				(hide yes)
			)
		)
		(property "License" "Apache-2.0"
			(at 327.66 179.07 0)
			(effects
				(font
					(size 1.27 1.27)
					(thickness 0.15)
				)
				(justify left bottom)
				(hide yes)
			)
		)
		(property "Author" "Antmicro"
			(at 330.2 179.07 0)
			(effects
				(font
					(size 1.27 1.27)
					(thickness 0.15)
				)
				(justify left bottom)
				(hide yes)
			)
		)
		(property "Val" "45k3"
			(at 303.53 198.12 90)
			(effects
				(font
					(size 1.27 1.27)
					(thickness 0.15)
				)
				(justify right)
			)
		)
		(property "Tolerance" "1%"
			(at 312.42 179.07 0)
			(effects
				(font
					(size 1.27 1.27)
				)
				(justify left bottom)
				(hide yes)
			)
		)
		(pin "2"
		)
		(pin "1"
		)
		(instances
			(project "jetson-orin-baseboard"
				(path ""
					(reference "R177")
					(unit 1)
				)
			)
		)
	)
	(symbol
		(lib_id "antmicroResistors0402:R_1k_0402")
		(at 86.36 34.29 90)
		(unit 1)
		(exclude_from_sim no)
		(in_bom yes)
		(on_board yes)
		(dnp no)
		(property "Reference" "R256"
			(at 87.63 30.48 90)
			(effects
				(font
					(size 1.27 1.27)
				)
				(justify right)
			)
		)
		(property "Value" "R_1k_0402"
			(at 99.06 13.97 0)
			(effects
				(font
					(size 1.27 1.27)
					(thickness 0.15)
				)
				(justify left bottom)
				(hide yes)
			)
		)
		(property "Footprint" "antmicro-footprints:R_0402_1005Metric"
			(at 101.6 13.97 0)
			(effects
				(font
					(size 1.27 1.27)
					(thickness 0.15)
				)
				(justify left bottom)
				(hide yes)
			)
		)
		(property "Datasheet" "https://www.bourns.com/docs/product-datasheets/cr.pdf"
			(at 104.14 13.97 0)
			(effects
				(font
					(size 1.27 1.27)
					(thickness 0.15)
				)
				(justify left bottom)
				(hide yes)
			)
		)
		(property "Description" ""
			(at 86.36 34.29 0)
			(effects
				(font
					(size 1.27 1.27)
				)
				(hide yes)
			)
		)
		(property "Manufacturer" "Bourns"
			(at 109.22 13.97 0)
			(effects
				(font
					(size 1.27 1.27)
					(thickness 0.15)
				)
				(justify left bottom)
				(hide yes)
			)
		)
		(property "MPN" "CR0402-FX-1001GLF"
			(at 106.68 13.97 0)
			(effects
				(font
					(size 1.27 1.27)
					(thickness 0.15)
				)
				(justify left bottom)
				(hide yes)
			)
		)
		(property "Val" "1k"
			(at 87.63 33.02 90)
			(effects
				(font
					(size 1.27 1.27)
					(thickness 0.15)
				)
				(justify right)
			)
		)
		(property "License" "Apache-2.0"
			(at 111.76 13.97 0)
			(effects
				(font
					(size 1.27 1.27)
					(thickness 0.15)
				)
				(justify left bottom)
				(hide yes)
			)
		)
		(property "Author" "Antmicro"
			(at 114.3 13.97 0)
			(effects
				(font
					(size 1.27 1.27)
					(thickness 0.15)
				)
				(justify left bottom)
				(hide yes)
			)
		)
		(property "Tolerance" "1%"
			(at 96.52 13.97 0)
			(effects
				(font
					(size 1.27 1.27)
				)
				(justify left bottom)
				(hide yes)
			)
		)
		(pin "1"
		)
		(pin "2"
		)
		(instances
			(project "jetson-orin-baseboard"
				(path ""
					(reference "R256")
					(unit 1)
				)
			)
		)
	)
	(symbol
		(lib_id "antmicroCapacitors0402:C_100n_0402")
		(at 207.01 200.66 270)
		(unit 1)
		(exclude_from_sim no)
		(in_bom yes)
		(on_board yes)
		(dnp no)
		(property "Reference" "C121"
			(at 207.645 201.295 90)
			(effects
				(font
					(size 1.27 1.27)
				)
				(justify left)
			)
		)
		(property "Value" "C_100n_0402"
			(at 196.85 220.98 0)
			(effects
				(font
					(size 1.27 1.27)
					(thickness 0.15)
				)
				(justify left bottom)
				(hide yes)
			)
		)
		(property "Footprint" "antmicro-footprints:C_0402_1005Metric"
			(at 194.31 220.98 0)
			(effects
				(font
					(size 1.27 1.27)
					(thickness 0.15)
				)
				(justify left bottom)
				(hide yes)
			)
		)
		(property "Datasheet" "https://www.murata.com/products/productdetail?partno=GRM155R61H104KE14%23"
			(at 191.77 220.98 0)
			(effects
				(font
					(size 1.27 1.27)
					(thickness 0.15)
				)
				(justify left bottom)
				(hide yes)
			)
		)
		(property "Description" ""
			(at 207.01 200.66 0)
			(effects
				(font
					(size 1.27 1.27)
				)
				(hide yes)
			)
		)
		(property "Manufacturer" "Murata"
			(at 186.69 220.98 0)
			(effects
				(font
					(size 1.27 1.27)
					(thickness 0.15)
				)
				(justify left bottom)
				(hide yes)
			)
		)
		(property "MPN" "GRM155R61H104KE14D"
			(at 189.23 220.98 0)
			(effects
				(font
					(size 1.27 1.27)
					(thickness 0.15)
				)
				(justify left bottom)
				(hide yes)
			)
		)
		(property "Val" "100n"
			(at 207.645 205.105 90)
			(effects
				(font
					(size 1.27 1.27)
					(thickness 0.15)
				)
				(justify left)
			)
		)
		(property "License" "Apache-2.0"
			(at 184.15 220.98 0)
			(effects
				(font
					(size 1.27 1.27)
					(thickness 0.15)
				)
				(justify left bottom)
				(hide yes)
			)
		)
		(property "Author" "Antmicro"
			(at 181.61 220.98 0)
			(effects
				(font
					(size 1.27 1.27)
					(thickness 0.15)
				)
				(justify left bottom)
				(hide yes)
			)
		)
		(property "Voltage" "50V"
			(at 179.07 220.98 0)
			(effects
				(font
					(size 1.27 1.27)
				)
				(justify left bottom)
				(hide yes)
			)
		)
		(property "Dielectric" "X5R"
			(at 176.53 220.98 0)
			(effects
				(font
					(size 1.27 1.27)
				)
				(justify left bottom)
				(hide yes)
			)
		)
		(pin "1"
		)
		(pin "2"
		)
		(instances
			(project "jetson-orin-baseboard"
				(path ""
					(reference "C121")
					(unit 1)
				)
			)
		)
	)
	(symbol
		(lib_id "antmicroResistors0402:R_10k_0402")
		(at 73.66 199.39 90)
		(unit 1)
		(exclude_from_sim no)
		(in_bom yes)
		(on_board yes)
		(dnp no)
		(property "Reference" "R255"
			(at 74.93 195.58 90)
			(effects
				(font
					(size 1.27 1.27)
				)
				(justify right)
			)
		)
		(property "Value" "R_10k_0402"
			(at 86.36 179.07 0)
			(effects
				(font
					(size 1.27 1.27)
					(thickness 0.15)
				)
				(justify left bottom)
				(hide yes)
			)
		)
		(property "Footprint" "antmicro-footprints:R_0402_1005Metric"
			(at 88.9 179.07 0)
			(effects
				(font
					(size 1.27 1.27)
					(thickness 0.15)
				)
				(justify left bottom)
				(hide yes)
			)
		)
		(property "Datasheet" "https://www.bourns.com/docs/product-datasheets/cr.pdf"
			(at 91.44 179.07 0)
			(effects
				(font
					(size 1.27 1.27)
					(thickness 0.15)
				)
				(justify left bottom)
				(hide yes)
			)
		)
		(property "Description" ""
			(at 73.66 199.39 0)
			(effects
				(font
					(size 1.27 1.27)
				)
				(hide yes)
			)
		)
		(property "Manufacturer" "Bourns"
			(at 96.52 179.07 0)
			(effects
				(font
					(size 1.27 1.27)
					(thickness 0.15)
				)
				(justify left bottom)
				(hide yes)
			)
		)
		(property "MPN" "CR0402-FX-1002GLF"
			(at 93.98 179.07 0)
			(effects
				(font
					(size 1.27 1.27)
					(thickness 0.15)
				)
				(justify left bottom)
				(hide yes)
			)
		)
		(property "Val" "10k"
			(at 74.93 198.12 90)
			(effects
				(font
					(size 1.27 1.27)
					(thickness 0.15)
				)
				(justify right)
			)
		)
		(property "License" "Apache-2.0"
			(at 99.06 179.07 0)
			(effects
				(font
					(size 1.27 1.27)
					(thickness 0.15)
				)
				(justify left bottom)
				(hide yes)
			)
		)
		(property "Author" "Antmicro"
			(at 101.6 179.07 0)
			(effects
				(font
					(size 1.27 1.27)
					(thickness 0.15)
				)
				(justify left bottom)
				(hide yes)
			)
		)
		(property "Tolerance" "1%"
			(at 83.82 179.07 0)
			(effects
				(font
					(size 1.27 1.27)
				)
				(justify left bottom)
				(hide yes)
			)
		)
		(pin "1"
		)
		(pin "2"
		)
		(instances
			(project "jetson-orin-baseboard"
				(path ""
					(reference "R255")
					(unit 1)
				)
			)
		)
	)
	(symbol
		(lib_id "antmicroResistors0402:R_0R_0402")
		(at 248.92 76.2 0)
		(mirror y)
		(unit 1)
		(exclude_from_sim no)
		(in_bom no)
		(on_board yes)
		(dnp yes)
		(property "Reference" "R183"
			(at 243.84 75.565 0)
			(effects
				(font
					(size 1.27 1.27)
				)
				(justify left bottom)
			)
		)
		(property "Value" "R_0R_0402"
			(at 228.6 88.9 0)
			(effects
				(font
					(size 1.27 1.27)
					(thickness 0.15)
				)
				(justify left bottom)
				(hide yes)
			)
		)
		(property "Footprint" "antmicro-footprints:R_0402_1005Metric"
			(at 228.6 91.44 0)
			(effects
				(font
					(size 1.27 1.27)
					(thickness 0.15)
				)
				(justify left bottom)
				(hide yes)
			)
		)
		(property "Datasheet" "https://industrial.panasonic.com/cdbs/www-data/pdf/RDA0000/AOA0000C301.pdf"
			(at 228.6 93.98 0)
			(effects
				(font
					(size 1.27 1.27)
					(thickness 0.15)
				)
				(justify left bottom)
				(hide yes)
			)
		)
		(property "Description" ""
			(at 248.92 76.2 0)
			(effects
				(font
					(size 1.27 1.27)
				)
				(hide yes)
			)
		)
		(property "Manufacturer" "Panasonic"
			(at 228.6 99.06 0)
			(effects
				(font
					(size 1.27 1.27)
					(thickness 0.15)
				)
				(justify left bottom)
				(hide yes)
			)
		)
		(property "MPN" "ERJ2GE0R00X"
			(at 228.6 96.52 0)
			(effects
				(font
					(size 1.27 1.27)
					(thickness 0.15)
				)
				(justify left bottom)
				(hide yes)
			)
		)
		(property "Val" "0R"
			(at 251.46 75.565 0)
			(effects
				(font
					(size 1.27 1.27)
					(thickness 0.15)
				)
				(justify left bottom)
			)
		)
		(property "License" "Apache-2.0"
			(at 228.6 101.6 0)
			(effects
				(font
					(size 1.27 1.27)
					(thickness 0.15)
				)
				(justify left bottom)
				(hide yes)
			)
		)
		(property "Author" "Antmicro"
			(at 228.6 104.14 0)
			(effects
				(font
					(size 1.27 1.27)
					(thickness 0.15)
				)
				(justify left bottom)
				(hide yes)
			)
		)
		(property "Tolerance" "~"
			(at 228.6 86.36 0)
			(effects
				(font
					(size 1.27 1.27)
				)
				(justify left bottom)
				(hide yes)
			)
		)
		(property "Current" "1A"
			(at 228.6 106.68 0)
			(effects
				(font
					(size 1.27 1.27)
					(thickness 0.15)
				)
				(justify left bottom)
				(hide yes)
			)
		)
		(pin "1"
		)
		(pin "2"
		)
		(instances
			(project "jetson-orin-baseboard"
				(path ""
					(reference "R183")
					(unit 1)
				)
			)
		)
	)
	(symbol
		(lib_id "antmicropower:GND")
		(at 73.66 200.66 0)
		(unit 1)
		(exclude_from_sim no)
		(in_bom yes)
		(on_board yes)
		(dnp no)
		(property "Reference" "#PWR0310"
			(at 73.66 207.01 0)
			(effects
				(font
					(size 1.27 1.27)
				)
				(justify left bottom)
				(hide yes)
			)
		)
		(property "Value" "GND"
			(at 73.66 204.47 0)
			(effects
				(font
					(size 1.27 1.27)
					(thickness 0.15)
				)
			)
		)
		(property "Footprint" ""
			(at 82.55 208.28 0)
			(effects
				(font
					(size 1.27 1.27)
					(thickness 0.15)
				)
				(justify left bottom)
				(hide yes)
			)
		)
		(property "Datasheet" ""
			(at 82.55 213.36 0)
			(effects
				(font
					(size 1.27 1.27)
					(thickness 0.15)
				)
				(justify left bottom)
				(hide yes)
			)
		)
		(property "Description" ""
			(at 73.66 200.66 0)
			(effects
				(font
					(size 1.27 1.27)
				)
				(hide yes)
			)
		)
		(property "Author" "Antmicro"
			(at 82.55 208.28 0)
			(effects
				(font
					(size 1.27 1.27)
					(thickness 0.15)
				)
				(justify left bottom)
				(hide yes)
			)
		)
		(property "License" "Apache-2.0"
			(at 82.55 210.82 0)
			(effects
				(font
					(size 1.27 1.27)
					(thickness 0.15)
				)
				(justify left bottom)
				(hide yes)
			)
		)
		(pin "1"
		)
		(instances
			(project "jetson-orin-baseboard"
				(path ""
					(reference "#PWR0310")
					(unit 1)
				)
			)
		)
	)
	(symbol
		(lib_id "antmicropower:PWR_FLAG")
		(at 386.08 67.31 0)
		(unit 1)
		(exclude_from_sim no)
		(in_bom yes)
		(on_board yes)
		(dnp no)
		(property "Reference" "#FLG03"
			(at 386.08 65.405 0)
			(effects
				(font
					(size 1.27 1.27)
				)
				(hide yes)
			)
		)
		(property "Value" "PWR_FLAG"
			(at 386.08 63.5 0)
			(effects
				(font
					(size 1.27 1.27)
				)
			)
		)
		(property "Footprint" ""
			(at 386.08 67.31 0)
			(effects
				(font
					(size 1.27 1.27)
				)
				(hide yes)
			)
		)
		(property "Datasheet" ""
			(at 386.08 67.31 0)
			(effects
				(font
					(size 1.27 1.27)
				)
				(hide yes)
			)
		)
		(property "Description" ""
			(at 386.08 67.31 0)
			(effects
				(font
					(size 1.27 1.27)
				)
				(hide yes)
			)
		)
		(pin "1"
		)
		(instances
			(project "jetson-orin-baseboard"
				(path ""
					(reference "#FLG03")
					(unit 1)
				)
			)
		)
	)
	(symbol
		(lib_id "antmicropower:GND")
		(at 198.12 213.36 0)
		(unit 1)
		(exclude_from_sim no)
		(in_bom yes)
		(on_board yes)
		(dnp no)
		(property "Reference" "#PWR0325"
			(at 198.12 219.71 0)
			(effects
				(font
					(size 1.27 1.27)
				)
				(justify left bottom)
				(hide yes)
			)
		)
		(property "Value" "GND"
			(at 198.12 217.17 0)
			(effects
				(font
					(size 1.27 1.27)
					(thickness 0.15)
				)
			)
		)
		(property "Footprint" ""
			(at 207.01 220.98 0)
			(effects
				(font
					(size 1.27 1.27)
					(thickness 0.15)
				)
				(justify left bottom)
				(hide yes)
			)
		)
		(property "Datasheet" ""
			(at 207.01 226.06 0)
			(effects
				(font
					(size 1.27 1.27)
					(thickness 0.15)
				)
				(justify left bottom)
				(hide yes)
			)
		)
		(property "Description" ""
			(at 198.12 213.36 0)
			(effects
				(font
					(size 1.27 1.27)
				)
				(hide yes)
			)
		)
		(property "Author" "Antmicro"
			(at 207.01 220.98 0)
			(effects
				(font
					(size 1.27 1.27)
					(thickness 0.15)
				)
				(justify left bottom)
				(hide yes)
			)
		)
		(property "License" "Apache-2.0"
			(at 207.01 223.52 0)
			(effects
				(font
					(size 1.27 1.27)
					(thickness 0.15)
				)
				(justify left bottom)
				(hide yes)
			)
		)
		(pin "1"
		)
		(instances
			(project "jetson-orin-baseboard"
				(path ""
					(reference "#PWR0325")
					(unit 1)
				)
			)
		)
	)
	(symbol
		(lib_id "antmicropower:GND")
		(at 223.52 154.94 0)
		(unit 1)
		(exclude_from_sim no)
		(in_bom yes)
		(on_board yes)
		(dnp no)
		(property "Reference" "#PWR0316"
			(at 223.52 161.29 0)
			(effects
				(font
					(size 1.27 1.27)
				)
				(justify left bottom)
				(hide yes)
			)
		)
		(property "Value" "GND"
			(at 223.52 158.75 0)
			(effects
				(font
					(size 1.27 1.27)
					(thickness 0.15)
				)
			)
		)
		(property "Footprint" ""
			(at 232.41 162.56 0)
			(effects
				(font
					(size 1.27 1.27)
					(thickness 0.15)
				)
				(justify left bottom)
				(hide yes)
			)
		)
		(property "Datasheet" ""
			(at 232.41 167.64 0)
			(effects
				(font
					(size 1.27 1.27)
					(thickness 0.15)
				)
				(justify left bottom)
				(hide yes)
			)
		)
		(property "Description" ""
			(at 223.52 154.94 0)
			(effects
				(font
					(size 1.27 1.27)
				)
				(hide yes)
			)
		)
		(property "Author" "Antmicro"
			(at 232.41 162.56 0)
			(effects
				(font
					(size 1.27 1.27)
					(thickness 0.15)
				)
				(justify left bottom)
				(hide yes)
			)
		)
		(property "License" "Apache-2.0"
			(at 232.41 165.1 0)
			(effects
				(font
					(size 1.27 1.27)
					(thickness 0.15)
				)
				(justify left bottom)
				(hide yes)
			)
		)
		(pin "1"
		)
		(instances
			(project "jetson-orin-baseboard"
				(path ""
					(reference "#PWR0316")
					(unit 1)
				)
			)
		)
	)
	(symbol
		(lib_id "antmicroResistors0402:R_499k_0402")
		(at 214.63 196.85 90)
		(unit 1)
		(exclude_from_sim no)
		(in_bom no)
		(on_board yes)
		(dnp yes)
		(property "Reference" "R240"
			(at 215.9 193.04 90)
			(effects
				(font
					(size 1.27 1.27)
					(thickness 0.15)
				)
				(justify right)
			)
		)
		(property "Value" "R_499k_0402"
			(at 227.33 176.53 0)
			(effects
				(font
					(size 1.27 1.27)
					(thickness 0.15)
				)
				(justify left bottom)
				(hide yes)
			)
		)
		(property "Footprint" "antmicro-footprints:R_0402_1005Metric"
			(at 229.87 176.53 0)
			(effects
				(font
					(size 1.27 1.27)
					(thickness 0.15)
				)
				(justify left bottom)
				(hide yes)
			)
		)
		(property "Datasheet" "https://www.mouser.com/datasheet/2/54/cr-1858361.pdf"
			(at 232.41 176.53 0)
			(effects
				(font
					(size 1.27 1.27)
					(thickness 0.15)
				)
				(justify left bottom)
				(hide yes)
			)
		)
		(property "Description" ""
			(at 214.63 196.85 0)
			(effects
				(font
					(size 1.27 1.27)
				)
				(hide yes)
			)
		)
		(property "MPN" "CR0402-FX-4993GLF"
			(at 234.95 176.53 0)
			(effects
				(font
					(size 1.27 1.27)
					(thickness 0.15)
				)
				(justify left bottom)
				(hide yes)
			)
		)
		(property "Manufacturer" "Bourns"
			(at 237.49 176.53 0)
			(effects
				(font
					(size 1.27 1.27)
					(thickness 0.15)
				)
				(justify left bottom)
				(hide yes)
			)
		)
		(property "License" "Apache-2.0"
			(at 240.03 176.53 0)
			(effects
				(font
					(size 1.27 1.27)
					(thickness 0.15)
				)
				(justify left bottom)
				(hide yes)
			)
		)
		(property "Author" "Antmicro"
			(at 242.57 176.53 0)
			(effects
				(font
					(size 1.27 1.27)
					(thickness 0.15)
				)
				(justify left bottom)
				(hide yes)
			)
		)
		(property "Val" "499k"
			(at 215.9 195.58 90)
			(effects
				(font
					(size 1.27 1.27)
					(thickness 0.15)
				)
				(justify right)
			)
		)
		(property "Tolerance" "1%"
			(at 224.79 176.53 0)
			(effects
				(font
					(size 1.27 1.27)
				)
				(justify left bottom)
				(hide yes)
			)
		)
		(pin "2"
		)
		(pin "1"
		)
		(instances
			(project "jetson-orin-baseboard"
				(path ""
					(reference "R240")
					(unit 1)
				)
			)
		)
	)
	(symbol
		(lib_id "antmicroTransistorsFETsMOSFETsSingle:PJE138K")
		(at 368.3 152.4 0)
		(unit 1)
		(exclude_from_sim no)
		(in_bom yes)
		(on_board yes)
		(dnp no)
		(property "Reference" "Q5"
			(at 377.19 148.59 0)
			(effects
				(font
					(size 1.27 1.27)
					(thickness 0.15)
				)
				(justify left)
			)
		)
		(property "Value" "PJE138K"
			(at 391.16 161.29 0)
			(effects
				(font
					(size 1.27 1.27)
					(thickness 0.15)
				)
				(justify left bottom)
				(hide yes)
			)
		)
		(property "Footprint" "antmicro-footprints:SOT-523"
			(at 391.16 163.83 0)
			(effects
				(font
					(size 1.27 1.27)
					(thickness 0.15)
				)
				(justify left bottom)
				(hide yes)
			)
		)
		(property "Datasheet" "https://www.mouser.com/datasheet/2/1057/PJE138K-1876698.pdf"
			(at 391.16 166.37 0)
			(effects
				(font
					(size 1.27 1.27)
					(thickness 0.15)
				)
				(justify left bottom)
				(hide yes)
			)
		)
		(property "Description" ""
			(at 368.3 152.4 0)
			(effects
				(font
					(size 1.27 1.27)
				)
				(hide yes)
			)
		)
		(property "MPN" "PJE138K_R1_00001"
			(at 377.19 151.13 0)
			(effects
				(font
					(size 1.27 1.27)
					(thickness 0.15)
				)
				(justify left)
			)
		)
		(property "Manufacturer" "PANJIT"
			(at 391.16 171.45 0)
			(effects
				(font
					(size 1.27 1.27)
					(thickness 0.15)
				)
				(justify left bottom)
				(hide yes)
			)
		)
		(property "Author" "Antmicro"
			(at 391.16 173.99 0)
			(effects
				(font
					(size 1.27 1.27)
					(thickness 0.15)
				)
				(justify left bottom)
				(hide yes)
			)
		)
		(property "License" "Apache-2.0"
			(at 391.16 176.53 0)
			(effects
				(font
					(size 1.27 1.27)
					(thickness 0.15)
				)
				(justify left bottom)
				(hide yes)
			)
		)
		(pin "2"
		)
		(pin "3"
		)
		(pin "1"
		)
		(instances
			(project "jetson-orin-baseboard"
				(path ""
					(reference "Q5")
					(unit 1)
				)
			)
		)
	)
	(symbol
		(lib_id "antmicroTestPoints:TP_0.75mm_SMD")
		(at 387.35 68.58 0)
		(unit 1)
		(exclude_from_sim no)
		(in_bom no)
		(on_board yes)
		(dnp no)
		(property "Reference" "TP55"
			(at 391.16 68.58 0)
			(effects
				(font
					(size 1.27 1.27)
				)
				(justify left)
			)
		)
		(property "Value" "TP_0.75mm_SMD"
			(at 397.51 72.39 0)
			(effects
				(font
					(size 1.27 1.27)
					(thickness 0.15)
				)
				(justify left bottom)
				(hide yes)
			)
		)
		(property "Footprint" "antmicro-footprints:TP_SMD_0.75mm"
			(at 397.51 74.93 0)
			(effects
				(font
					(size 1.27 1.27)
					(thickness 0.15)
				)
				(justify left bottom)
				(hide yes)
			)
		)
		(property "Datasheet" ""
			(at 405.13 81.28 0)
			(effects
				(font
					(size 1.27 1.27)
					(thickness 0.15)
				)
				(justify left bottom)
				(hide yes)
			)
		)
		(property "Description" ""
			(at 387.35 68.58 0)
			(effects
				(font
					(size 1.27 1.27)
				)
				(hide yes)
			)
		)
		(property "MPN" ""
			(at 398.145 80.01 0)
			(effects
				(font
					(size 1.27 1.27)
					(thickness 0.15)
				)
				(justify left bottom)
				(hide yes)
			)
		)
		(property "Manufacturer" ""
			(at 398.145 74.93 0)
			(effects
				(font
					(size 1.27 1.27)
					(thickness 0.15)
				)
				(justify left bottom)
				(hide yes)
			)
		)
		(property "Author" "Antmicro"
			(at 397.51 77.47 0)
			(effects
				(font
					(size 1.27 1.27)
					(thickness 0.15)
				)
				(justify left bottom)
				(hide yes)
			)
		)
		(property "License" "Apache-2.0"
			(at 397.51 80.01 0)
			(effects
				(font
					(size 1.27 1.27)
					(thickness 0.15)
				)
				(justify left bottom)
				(hide yes)
			)
		)
		(pin "1"
		)
		(instances
			(project "jetson-orin-baseboard"
				(path ""
					(reference "TP55")
					(unit 1)
				)
			)
		)
	)
	(symbol
		(lib_id "antmicropower:GND")
		(at 214.63 213.36 0)
		(unit 1)
		(exclude_from_sim no)
		(in_bom yes)
		(on_board yes)
		(dnp no)
		(property "Reference" "#PWR0338"
			(at 214.63 219.71 0)
			(effects
				(font
					(size 1.27 1.27)
				)
				(justify left bottom)
				(hide yes)
			)
		)
		(property "Value" "GND"
			(at 214.63 217.17 0)
			(effects
				(font
					(size 1.27 1.27)
					(thickness 0.15)
				)
			)
		)
		(property "Footprint" ""
			(at 223.52 220.98 0)
			(effects
				(font
					(size 1.27 1.27)
					(thickness 0.15)
				)
				(justify left bottom)
				(hide yes)
			)
		)
		(property "Datasheet" ""
			(at 223.52 226.06 0)
			(effects
				(font
					(size 1.27 1.27)
					(thickness 0.15)
				)
				(justify left bottom)
				(hide yes)
			)
		)
		(property "Description" ""
			(at 214.63 213.36 0)
			(effects
				(font
					(size 1.27 1.27)
				)
				(hide yes)
			)
		)
		(property "Author" "Antmicro"
			(at 223.52 220.98 0)
			(effects
				(font
					(size 1.27 1.27)
					(thickness 0.15)
				)
				(justify left bottom)
				(hide yes)
			)
		)
		(property "License" "Apache-2.0"
			(at 223.52 223.52 0)
			(effects
				(font
					(size 1.27 1.27)
					(thickness 0.15)
				)
				(justify left bottom)
				(hide yes)
			)
		)
		(pin "1"
		)
		(instances
			(project "jetson-orin-baseboard"
				(path ""
					(reference "#PWR0338")
					(unit 1)
				)
			)
		)
	)
	(symbol
		(lib_id "antmicropower:GND")
		(at 241.3 252.73 0)
		(unit 1)
		(exclude_from_sim no)
		(in_bom yes)
		(on_board yes)
		(dnp no)
		(property "Reference" "#PWR0371"
			(at 241.3 259.08 0)
			(effects
				(font
					(size 1.27 1.27)
				)
				(justify left bottom)
				(hide yes)
			)
		)
		(property "Value" "GND"
			(at 241.3 256.54 0)
			(effects
				(font
					(size 1.27 1.27)
					(thickness 0.15)
				)
			)
		)
		(property "Footprint" ""
			(at 250.19 260.35 0)
			(effects
				(font
					(size 1.27 1.27)
					(thickness 0.15)
				)
				(justify left bottom)
				(hide yes)
			)
		)
		(property "Datasheet" ""
			(at 250.19 265.43 0)
			(effects
				(font
					(size 1.27 1.27)
					(thickness 0.15)
				)
				(justify left bottom)
				(hide yes)
			)
		)
		(property "Description" ""
			(at 241.3 252.73 0)
			(effects
				(font
					(size 1.27 1.27)
				)
				(hide yes)
			)
		)
		(property "Author" "Antmicro"
			(at 250.19 260.35 0)
			(effects
				(font
					(size 1.27 1.27)
					(thickness 0.15)
				)
				(justify left bottom)
				(hide yes)
			)
		)
		(property "License" "Apache-2.0"
			(at 250.19 262.89 0)
			(effects
				(font
					(size 1.27 1.27)
					(thickness 0.15)
				)
				(justify left bottom)
				(hide yes)
			)
		)
		(pin "1"
		)
		(instances
			(project "jetson-orin-baseboard"
				(path ""
					(reference "#PWR0371")
					(unit 1)
				)
			)
		)
	)
	(symbol
		(lib_id "antmicroCapacitors0402:C_1n_0402")
		(at 262.89 247.65 90)
		(unit 1)
		(exclude_from_sim no)
		(in_bom yes)
		(on_board yes)
		(dnp no)
		(property "Reference" "C160"
			(at 263.525 243.205 90)
			(effects
				(font
					(size 1.27 1.27)
					(thickness 0.15)
				)
				(justify right)
			)
		)
		(property "Value" "C_1n_0402"
			(at 273.05 227.33 0)
			(effects
				(font
					(size 1.27 1.27)
					(thickness 0.15)
				)
				(justify left bottom)
				(hide yes)
			)
		)
		(property "Footprint" "antmicro-footprints:C_0402_1005Metric"
			(at 275.59 227.33 0)
			(effects
				(font
					(size 1.27 1.27)
					(thickness 0.15)
				)
				(justify left bottom)
				(hide yes)
			)
		)
		(property "Datasheet" "https://www.murata.com/products/productdetail?partno=GRM1555C1H102JA01%23"
			(at 278.13 227.33 0)
			(effects
				(font
					(size 1.27 1.27)
					(thickness 0.15)
				)
				(justify left bottom)
				(hide yes)
			)
		)
		(property "Description" "SMD Multilayer Ceramic Capacitor, 1000 pF, 50 V, 0402 [1005 Metric], ± 5%, C0G / NP0, GRM Series"
			(at 262.89 247.65 0)
			(effects
				(font
					(size 1.27 1.27)
				)
				(hide yes)
			)
		)
		(property "MPN" "GRM1555C1H102JA01D"
			(at 280.67 227.33 0)
			(effects
				(font
					(size 1.27 1.27)
					(thickness 0.15)
				)
				(justify left bottom)
				(hide yes)
			)
		)
		(property "Manufacturer" "Murata"
			(at 283.21 227.33 0)
			(effects
				(font
					(size 1.27 1.27)
					(thickness 0.15)
				)
				(justify left bottom)
				(hide yes)
			)
		)
		(property "License" "Apache-2.0"
			(at 285.75 227.33 0)
			(effects
				(font
					(size 1.27 1.27)
					(thickness 0.15)
				)
				(justify left bottom)
				(hide yes)
			)
		)
		(property "Author" "Antmicro"
			(at 288.29 227.33 0)
			(effects
				(font
					(size 1.27 1.27)
					(thickness 0.15)
				)
				(justify left bottom)
				(hide yes)
			)
		)
		(property "Val" "1n"
			(at 263.525 247.65 90)
			(effects
				(font
					(size 1.27 1.27)
					(thickness 0.15)
				)
				(justify right)
			)
		)
		(property "Voltage" "50V"
			(at 290.83 227.33 0)
			(effects
				(font
					(size 1.27 1.27)
				)
				(justify left bottom)
				(hide yes)
			)
		)
		(property "Dielectric" "C0G"
			(at 293.37 227.33 0)
			(effects
				(font
					(size 1.27 1.27)
				)
				(justify left bottom)
				(hide yes)
			)
		)
		(pin "2"
		)
		(pin "1"
		)
		(instances
			(project ""
				(path ""
					(reference "C160")
					(unit 1)
				)
			)
		)
	)
	(symbol
		(lib_id "antmicroCapacitors0402:C_4u7_25V_0402")
		(at 242.57 212.09 90)
		(unit 1)
		(exclude_from_sim no)
		(in_bom yes)
		(on_board yes)
		(dnp no)
		(property "Reference" "C155"
			(at 243.205 207.645 90)
			(effects
				(font
					(size 1.27 1.27)
					(thickness 0.15)
				)
				(justify right)
			)
		)
		(property "Value" "C_4u7_25V_0402"
			(at 252.73 191.77 0)
			(effects
				(font
					(size 1.27 1.27)
					(thickness 0.15)
				)
				(justify left bottom)
				(hide yes)
			)
		)
		(property "Footprint" "antmicro-footprints:C_0402_1005Metric"
			(at 255.27 191.77 0)
			(effects
				(font
					(size 1.27 1.27)
					(thickness 0.15)
				)
				(justify left bottom)
				(hide yes)
			)
		)
		(property "Datasheet" "https://www.murata.com/products/productdetail?partno=GRM155C61E475ME15%23"
			(at 257.81 191.77 0)
			(effects
				(font
					(size 1.27 1.27)
					(thickness 0.15)
				)
				(justify left bottom)
				(hide yes)
			)
		)
		(property "Description" ""
			(at 242.57 212.09 0)
			(effects
				(font
					(size 1.27 1.27)
				)
				(hide yes)
			)
		)
		(property "MPN" "GRM155C61E475ME15J"
			(at 260.35 191.77 0)
			(effects
				(font
					(size 1.27 1.27)
					(thickness 0.15)
				)
				(justify left bottom)
				(hide yes)
			)
		)
		(property "Manufacturer" "Murata"
			(at 262.89 191.77 0)
			(effects
				(font
					(size 1.27 1.27)
					(thickness 0.15)
				)
				(justify left bottom)
				(hide yes)
			)
		)
		(property "License" "Apache-2.0"
			(at 265.43 191.77 0)
			(effects
				(font
					(size 1.27 1.27)
					(thickness 0.15)
				)
				(justify left bottom)
				(hide yes)
			)
		)
		(property "Author" "Antmicro"
			(at 267.97 191.77 0)
			(effects
				(font
					(size 1.27 1.27)
					(thickness 0.15)
				)
				(justify left bottom)
				(hide yes)
			)
		)
		(property "Val" "4u7"
			(at 243.205 211.455 90)
			(effects
				(font
					(size 1.27 1.27)
					(thickness 0.15)
				)
				(justify right)
			)
		)
		(property "Voltage" "25V"
			(at 270.51 191.77 0)
			(effects
				(font
					(size 1.27 1.27)
				)
				(justify left bottom)
				(hide yes)
			)
		)
		(property "Dielectric" "X5S"
			(at 273.05 191.77 0)
			(effects
				(font
					(size 1.27 1.27)
				)
				(justify left bottom)
				(hide yes)
			)
		)
		(pin "2"
		)
		(pin "1"
		)
		(instances
			(project "jetson-orin-baseboard"
				(path ""
					(reference "C155")
					(unit 1)
				)
			)
		)
	)
	(symbol
		(lib_id "antmicroTVSDiodes:ESD9X5.0ST5G")
		(at 360.68 201.93 270)
		(unit 1)
		(exclude_from_sim no)
		(in_bom yes)
		(on_board yes)
		(dnp no)
		(property "Reference" "D33"
			(at 361.95 203.2 90)
			(effects
				(font
					(size 1.27 1.27)
				)
				(justify left)
			)
		)
		(property "Value" "ESD9X5.0ST5G"
			(at 345.44 223.52 0)
			(effects
				(font
					(size 1.27 1.27)
					(thickness 0.15)
				)
				(justify left bottom)
				(hide yes)
			)
		)
		(property "Footprint" "antmicro-footprints:SOD-923"
			(at 353.06 223.52 0)
			(effects
				(font
					(size 1.27 1.27)
					(thickness 0.15)
				)
				(justify left bottom)
				(hide yes)
			)
		)
		(property "Datasheet" "https://www.onsemi.com/pdf/datasheet/esd9x3.3st5g-d.pdf"
			(at 350.52 223.52 0)
			(effects
				(font
					(size 1.27 1.27)
					(thickness 0.15)
				)
				(justify left bottom)
				(hide yes)
			)
		)
		(property "Description" ""
			(at 360.68 201.93 0)
			(effects
				(font
					(size 1.27 1.27)
				)
				(hide yes)
			)
		)
		(property "Manufacturer" "ON Semiconductor"
			(at 347.98 223.52 0)
			(effects
				(font
					(size 1.27 1.27)
					(thickness 0.15)
				)
				(justify left bottom)
				(hide yes)
			)
		)
		(property "MPN" "ESD9X5.0ST5G"
			(at 361.95 205.74 90)
			(effects
				(font
					(size 1.27 1.27)
					(thickness 0.15)
				)
				(justify left)
			)
		)
		(property "Author" "Antmicro"
			(at 342.9 223.52 0)
			(effects
				(font
					(size 1.27 1.27)
					(thickness 0.15)
				)
				(justify left bottom)
				(hide yes)
			)
		)
		(property "License" "Apache-2.0"
			(at 340.36 223.52 0)
			(effects
				(font
					(size 1.27 1.27)
					(thickness 0.15)
				)
				(justify left bottom)
				(hide yes)
			)
		)
		(pin "1"
		)
		(pin "2"
		)
		(instances
			(project "jetson-orin-baseboard"
				(path ""
					(reference "D33")
					(unit 1)
				)
			)
		)
	)
	(symbol
		(lib_id "antmicroResistors0603:R_0R_22.4A_0603")
		(at 132.08 151.13 0)
		(unit 1)
		(exclude_from_sim no)
		(in_bom no)
		(on_board yes)
		(dnp yes)
		(property "Reference" "R175"
			(at 137.16 150.495 0)
			(effects
				(font
					(size 1.27 1.27)
				)
				(justify left bottom)
			)
		)
		(property "Value" "R_0R_22.4A_0603"
			(at 134.62 140.335 0)
			(effects
				(font
					(size 1.27 1.27)
					(thickness 0.15)
				)
				(hide yes)
			)
		)
		(property "Footprint" "antmicro-footprints:R_0603_1608Metric"
			(at 147.32 161.29 0)
			(effects
				(font
					(size 1.27 1.27)
					(thickness 0.15)
				)
				(justify left bottom)
				(hide yes)
			)
		)
		(property "Datasheet" "https://fscdn.rohm.com/en/products/databook/datasheet/passive/resistor/chip_resistor/pmr-jpw-e.pdf"
			(at 147.32 163.83 0)
			(effects
				(font
					(size 1.27 1.27)
					(thickness 0.15)
				)
				(justify left bottom)
				(hide yes)
			)
		)
		(property "Description" ""
			(at 132.08 151.13 0)
			(effects
				(font
					(size 1.27 1.27)
				)
				(hide yes)
			)
		)
		(property "Manufacturer" "ROHM Semiconductor"
			(at 147.32 168.91 0)
			(effects
				(font
					(size 1.27 1.27)
					(thickness 0.15)
				)
				(justify left bottom)
				(hide yes)
			)
		)
		(property "MPN" "PMR03EZPJ000"
			(at 147.32 166.37 0)
			(effects
				(font
					(size 1.27 1.27)
					(thickness 0.15)
				)
				(justify left bottom)
				(hide yes)
			)
		)
		(property "Val" "0R"
			(at 129.54 150.495 0)
			(effects
				(font
					(size 1.27 1.27)
					(thickness 0.15)
				)
				(justify left bottom)
			)
		)
		(property "Author" "Antmicro"
			(at 147.32 173.99 0)
			(effects
				(font
					(size 1.27 1.27)
					(thickness 0.15)
				)
				(justify left bottom)
				(hide yes)
			)
		)
		(property "License" "Apache-2.0"
			(at 147.32 176.53 0)
			(effects
				(font
					(size 1.27 1.27)
					(thickness 0.15)
				)
				(justify left bottom)
				(hide yes)
			)
		)
		(property "Max. Curr." "22.4A"
			(at 134.62 153.035 0)
			(effects
				(font
					(size 1.27 1.27)
					(thickness 0.15)
				)
			)
		)
		(property "Tolerance" "template_tolerance"
			(at 152.4 161.29 0)
			(effects
				(font
					(size 1.27 1.27)
				)
				(justify left bottom)
				(hide yes)
			)
		)
		(pin "1"
		)
		(pin "2"
		)
		(instances
			(project "jetson-orin-baseboard"
				(path ""
					(reference "R175")
					(unit 1)
				)
			)
		)
	)
	(symbol
		(lib_id "antmicroResistors0402:R_10k_0402")
		(at 363.22 140.97 90)
		(unit 1)
		(exclude_from_sim no)
		(in_bom yes)
		(on_board yes)
		(dnp no)
		(property "Reference" "R181"
			(at 364.49 137.16 90)
			(effects
				(font
					(size 1.27 1.27)
				)
				(justify right)
			)
		)
		(property "Value" "R_10k_0402"
			(at 375.92 120.65 0)
			(effects
				(font
					(size 1.27 1.27)
					(thickness 0.15)
				)
				(justify left bottom)
				(hide yes)
			)
		)
		(property "Footprint" "antmicro-footprints:R_0402_1005Metric"
			(at 378.46 120.65 0)
			(effects
				(font
					(size 1.27 1.27)
					(thickness 0.15)
				)
				(justify left bottom)
				(hide yes)
			)
		)
		(property "Datasheet" "https://www.bourns.com/docs/product-datasheets/cr.pdf"
			(at 381 120.65 0)
			(effects
				(font
					(size 1.27 1.27)
					(thickness 0.15)
				)
				(justify left bottom)
				(hide yes)
			)
		)
		(property "Description" ""
			(at 363.22 140.97 0)
			(effects
				(font
					(size 1.27 1.27)
				)
				(hide yes)
			)
		)
		(property "Manufacturer" "Bourns"
			(at 386.08 120.65 0)
			(effects
				(font
					(size 1.27 1.27)
					(thickness 0.15)
				)
				(justify left bottom)
				(hide yes)
			)
		)
		(property "MPN" "CR0402-FX-1002GLF"
			(at 383.54 120.65 0)
			(effects
				(font
					(size 1.27 1.27)
					(thickness 0.15)
				)
				(justify left bottom)
				(hide yes)
			)
		)
		(property "Val" "10k"
			(at 364.49 139.7 90)
			(effects
				(font
					(size 1.27 1.27)
					(thickness 0.15)
				)
				(justify right)
			)
		)
		(property "License" "Apache-2.0"
			(at 388.62 120.65 0)
			(effects
				(font
					(size 1.27 1.27)
					(thickness 0.15)
				)
				(justify left bottom)
				(hide yes)
			)
		)
		(property "Author" "Antmicro"
			(at 391.16 120.65 0)
			(effects
				(font
					(size 1.27 1.27)
					(thickness 0.15)
				)
				(justify left bottom)
				(hide yes)
			)
		)
		(property "Tolerance" "1%"
			(at 373.38 120.65 0)
			(effects
				(font
					(size 1.27 1.27)
				)
				(justify left bottom)
				(hide yes)
			)
		)
		(pin "1"
		)
		(pin "2"
		)
		(instances
			(project "jetson-orin-baseboard"
				(path ""
					(reference "R181")
					(unit 1)
				)
			)
		)
	)
	(symbol
		(lib_id "antmicropower:GND")
		(at 223.52 213.36 0)
		(unit 1)
		(exclude_from_sim no)
		(in_bom yes)
		(on_board yes)
		(dnp no)
		(property "Reference" "#PWR0335"
			(at 223.52 219.71 0)
			(effects
				(font
					(size 1.27 1.27)
				)
				(justify left bottom)
				(hide yes)
			)
		)
		(property "Value" "GND"
			(at 223.52 217.17 0)
			(effects
				(font
					(size 1.27 1.27)
					(thickness 0.15)
				)
			)
		)
		(property "Footprint" ""
			(at 232.41 220.98 0)
			(effects
				(font
					(size 1.27 1.27)
					(thickness 0.15)
				)
				(justify left bottom)
				(hide yes)
			)
		)
		(property "Datasheet" ""
			(at 232.41 226.06 0)
			(effects
				(font
					(size 1.27 1.27)
					(thickness 0.15)
				)
				(justify left bottom)
				(hide yes)
			)
		)
		(property "Description" ""
			(at 223.52 213.36 0)
			(effects
				(font
					(size 1.27 1.27)
				)
				(hide yes)
			)
		)
		(property "Author" "Antmicro"
			(at 232.41 220.98 0)
			(effects
				(font
					(size 1.27 1.27)
					(thickness 0.15)
				)
				(justify left bottom)
				(hide yes)
			)
		)
		(property "License" "Apache-2.0"
			(at 232.41 223.52 0)
			(effects
				(font
					(size 1.27 1.27)
					(thickness 0.15)
				)
				(justify left bottom)
				(hide yes)
			)
		)
		(pin "1"
		)
		(instances
			(project "jetson-orin-baseboard"
				(path ""
					(reference "#PWR0335")
					(unit 1)
				)
			)
		)
	)
	(symbol
		(lib_id "antmicropower:+5V")
		(at 203.2 232.41 0)
		(unit 1)
		(exclude_from_sim no)
		(in_bom yes)
		(on_board yes)
		(dnp no)
		(property "Reference" "#PWR0375"
			(at 203.2 236.22 0)
			(effects
				(font
					(size 1.27 1.27)
				)
				(justify left bottom)
				(hide yes)
			)
		)
		(property "Value" "+5V_SoM"
			(at 203.2 228.6 0)
			(effects
				(font
					(size 1.27 1.27)
					(thickness 0.15)
				)
			)
		)
		(property "Footprint" ""
			(at 218.44 240.03 0)
			(effects
				(font
					(size 1.27 1.27)
					(thickness 0.15)
				)
				(justify left bottom)
				(hide yes)
			)
		)
		(property "Datasheet" ""
			(at 218.44 242.57 0)
			(effects
				(font
					(size 1.27 1.27)
					(thickness 0.15)
				)
				(justify left bottom)
				(hide yes)
			)
		)
		(property "Description" ""
			(at 203.2 232.41 0)
			(effects
				(font
					(size 1.27 1.27)
				)
				(hide yes)
			)
		)
		(property "Author" "Antmicro"
			(at 218.44 240.03 0)
			(effects
				(font
					(size 1.27 1.27)
					(thickness 0.15)
				)
				(justify left bottom)
				(hide yes)
			)
		)
		(property "License" "Apache-2.0"
			(at 218.44 242.57 0)
			(effects
				(font
					(size 1.27 1.27)
					(thickness 0.15)
				)
				(justify left bottom)
				(hide yes)
			)
		)
		(pin "1"
		)
		(instances
			(project "jetson-orin-baseboard"
				(path ""
					(reference "#PWR0375")
					(unit 1)
				)
			)
		)
	)
	(symbol
		(lib_id "antmicropower:GND")
		(at 73.66 153.67 0)
		(unit 1)
		(exclude_from_sim no)
		(in_bom yes)
		(on_board yes)
		(dnp no)
		(property "Reference" "#PWR0253"
			(at 73.66 160.02 0)
			(effects
				(font
					(size 1.27 1.27)
				)
				(justify left bottom)
				(hide yes)
			)
		)
		(property "Value" "GND"
			(at 73.66 157.48 0)
			(effects
				(font
					(size 1.27 1.27)
					(thickness 0.15)
				)
			)
		)
		(property "Footprint" ""
			(at 82.55 161.29 0)
			(effects
				(font
					(size 1.27 1.27)
					(thickness 0.15)
				)
				(justify left bottom)
				(hide yes)
			)
		)
		(property "Datasheet" ""
			(at 82.55 166.37 0)
			(effects
				(font
					(size 1.27 1.27)
					(thickness 0.15)
				)
				(justify left bottom)
				(hide yes)
			)
		)
		(property "Description" ""
			(at 73.66 153.67 0)
			(effects
				(font
					(size 1.27 1.27)
				)
				(hide yes)
			)
		)
		(property "Author" "Antmicro"
			(at 82.55 161.29 0)
			(effects
				(font
					(size 1.27 1.27)
					(thickness 0.15)
				)
				(justify left bottom)
				(hide yes)
			)
		)
		(property "License" "Apache-2.0"
			(at 82.55 163.83 0)
			(effects
				(font
					(size 1.27 1.27)
					(thickness 0.15)
				)
				(justify left bottom)
				(hide yes)
			)
		)
		(pin "1"
		)
		(instances
			(project "jetson-orin-baseboard"
				(path ""
					(reference "#PWR0253")
					(unit 1)
				)
			)
		)
	)
	(symbol
		(lib_id "antmicropower:+5V")
		(at 203.2 260.35 0)
		(unit 1)
		(exclude_from_sim no)
		(in_bom yes)
		(on_board yes)
		(dnp no)
		(property "Reference" "#PWR0374"
			(at 203.2 264.16 0)
			(effects
				(font
					(size 1.27 1.27)
				)
				(justify left bottom)
				(hide yes)
			)
		)
		(property "Value" "+5V_SoM"
			(at 203.2 256.54 0)
			(effects
				(font
					(size 1.27 1.27)
					(thickness 0.15)
				)
			)
		)
		(property "Footprint" ""
			(at 218.44 267.97 0)
			(effects
				(font
					(size 1.27 1.27)
					(thickness 0.15)
				)
				(justify left bottom)
				(hide yes)
			)
		)
		(property "Datasheet" ""
			(at 218.44 270.51 0)
			(effects
				(font
					(size 1.27 1.27)
					(thickness 0.15)
				)
				(justify left bottom)
				(hide yes)
			)
		)
		(property "Description" ""
			(at 203.2 260.35 0)
			(effects
				(font
					(size 1.27 1.27)
				)
				(hide yes)
			)
		)
		(property "Author" "Antmicro"
			(at 218.44 267.97 0)
			(effects
				(font
					(size 1.27 1.27)
					(thickness 0.15)
				)
				(justify left bottom)
				(hide yes)
			)
		)
		(property "License" "Apache-2.0"
			(at 218.44 270.51 0)
			(effects
				(font
					(size 1.27 1.27)
					(thickness 0.15)
				)
				(justify left bottom)
				(hide yes)
			)
		)
		(pin "1"
		)
		(instances
			(project "jetson-orin-baseboard"
				(path ""
					(reference "#PWR0374")
					(unit 1)
				)
			)
		)
	)
	(symbol
		(lib_id "antmicropower:GND")
		(at 207.01 154.94 0)
		(unit 1)
		(exclude_from_sim no)
		(in_bom yes)
		(on_board yes)
		(dnp no)
		(property "Reference" "#PWR0197"
			(at 207.01 161.29 0)
			(effects
				(font
					(size 1.27 1.27)
				)
				(justify left bottom)
				(hide yes)
			)
		)
		(property "Value" "GND"
			(at 207.01 158.75 0)
			(effects
				(font
					(size 1.27 1.27)
					(thickness 0.15)
				)
			)
		)
		(property "Footprint" ""
			(at 215.9 162.56 0)
			(effects
				(font
					(size 1.27 1.27)
					(thickness 0.15)
				)
				(justify left bottom)
				(hide yes)
			)
		)
		(property "Datasheet" ""
			(at 215.9 167.64 0)
			(effects
				(font
					(size 1.27 1.27)
					(thickness 0.15)
				)
				(justify left bottom)
				(hide yes)
			)
		)
		(property "Description" ""
			(at 207.01 154.94 0)
			(effects
				(font
					(size 1.27 1.27)
				)
				(hide yes)
			)
		)
		(property "Author" "Antmicro"
			(at 215.9 162.56 0)
			(effects
				(font
					(size 1.27 1.27)
					(thickness 0.15)
				)
				(justify left bottom)
				(hide yes)
			)
		)
		(property "License" "Apache-2.0"
			(at 215.9 165.1 0)
			(effects
				(font
					(size 1.27 1.27)
					(thickness 0.15)
				)
				(justify left bottom)
				(hide yes)
			)
		)
		(pin "1"
		)
		(instances
			(project "jetson-orin-baseboard"
				(path ""
					(reference "#PWR0197")
					(unit 1)
				)
			)
		)
	)
	(symbol
		(lib_id "antmicroTVSDiodes:TPD1E0B04_XDFN-2")
		(at 246.38 55.88 90)
		(unit 1)
		(exclude_from_sim no)
		(in_bom yes)
		(on_board yes)
		(dnp no)
		(property "Reference" "D61"
			(at 248.285 52.07 90)
			(effects
				(font
					(size 1.27 1.27)
				)
				(justify right)
			)
		)
		(property "Value" "TPD1E0B04_XDFN-2"
			(at 256.54 40.64 0)
			(effects
				(font
					(size 1.27 1.27)
					(thickness 0.15)
				)
				(justify left bottom)
				(hide yes)
			)
		)
		(property "Footprint" "antmicro-footprints:XDFN-2_1x0.60mm"
			(at 251.46 40.64 0)
			(effects
				(font
					(size 1.27 1.27)
					(thickness 0.15)
				)
				(justify left bottom)
				(hide yes)
			)
		)
		(property "Datasheet" "https://www.ti.com/general/docs/suppproductinfo.tsp?distId=26&gotoUrl=https://www.ti.com/lit/gpn/tpd1e0b04"
			(at 254 40.64 0)
			(effects
				(font
					(size 1.27 1.27)
					(thickness 0.15)
				)
				(justify left bottom)
				(hide yes)
			)
		)
		(property "Description" ""
			(at 246.38 55.88 0)
			(effects
				(font
					(size 1.27 1.27)
				)
				(hide yes)
			)
		)
		(property "Manufacturer" "Texas Instruments"
			(at 259.08 40.64 0)
			(effects
				(font
					(size 1.27 1.27)
					(thickness 0.15)
				)
				(justify left bottom)
				(hide yes)
			)
		)
		(property "MPN" "TPD1E0B04DPYR"
			(at 248.285 54.61 90)
			(effects
				(font
					(size 1.27 1.27)
					(thickness 0.15)
				)
				(justify right)
			)
		)
		(property "Author" "Antmicro"
			(at 261.62 40.64 0)
			(effects
				(font
					(size 1.27 1.27)
					(thickness 0.15)
				)
				(justify left bottom)
				(hide yes)
			)
		)
		(property "License" "Apache-2.0"
			(at 264.16 40.64 0)
			(effects
				(font
					(size 1.27 1.27)
					(thickness 0.15)
				)
				(justify left bottom)
				(hide yes)
			)
		)
		(pin "1"
		)
		(pin "2"
		)
		(instances
			(project "jetson-orin-baseboard"
				(path ""
					(reference "D61")
					(unit 1)
				)
			)
		)
	)
	(symbol
		(lib_id "antmicropower:GND")
		(at 241.3 279.4 0)
		(unit 1)
		(exclude_from_sim no)
		(in_bom yes)
		(on_board yes)
		(dnp no)
		(property "Reference" "#PWR0369"
			(at 241.3 285.75 0)
			(effects
				(font
					(size 1.27 1.27)
				)
				(justify left bottom)
				(hide yes)
			)
		)
		(property "Value" "GND"
			(at 241.3 283.21 0)
			(effects
				(font
					(size 1.27 1.27)
					(thickness 0.15)
				)
			)
		)
		(property "Footprint" ""
			(at 250.19 287.02 0)
			(effects
				(font
					(size 1.27 1.27)
					(thickness 0.15)
				)
				(justify left bottom)
				(hide yes)
			)
		)
		(property "Datasheet" ""
			(at 250.19 292.1 0)
			(effects
				(font
					(size 1.27 1.27)
					(thickness 0.15)
				)
				(justify left bottom)
				(hide yes)
			)
		)
		(property "Description" ""
			(at 241.3 279.4 0)
			(effects
				(font
					(size 1.27 1.27)
				)
				(hide yes)
			)
		)
		(property "Author" "Antmicro"
			(at 250.19 287.02 0)
			(effects
				(font
					(size 1.27 1.27)
					(thickness 0.15)
				)
				(justify left bottom)
				(hide yes)
			)
		)
		(property "License" "Apache-2.0"
			(at 250.19 289.56 0)
			(effects
				(font
					(size 1.27 1.27)
					(thickness 0.15)
				)
				(justify left bottom)
				(hide yes)
			)
		)
		(pin "1"
		)
		(instances
			(project "jetson-orin-baseboard"
				(path ""
					(reference "#PWR0369")
					(unit 1)
				)
			)
		)
	)
	(symbol
		(lib_id "antmicropower:GND")
		(at 153.67 270.51 0)
		(unit 1)
		(exclude_from_sim no)
		(in_bom yes)
		(on_board yes)
		(dnp no)
		(fields_autoplaced yes)
		(property "Reference" "#PWR08"
			(at 153.67 276.86 0)
			(effects
				(font
					(size 1.27 1.27)
				)
				(justify left bottom)
				(hide yes)
			)
		)
		(property "Value" "GND"
			(at 153.67 274.32 0)
			(effects
				(font
					(size 1.27 1.27)
					(thickness 0.15)
				)
			)
		)
		(property "Footprint" ""
			(at 162.56 278.13 0)
			(effects
				(font
					(size 1.27 1.27)
					(thickness 0.15)
				)
				(justify left bottom)
				(hide yes)
			)
		)
		(property "Datasheet" ""
			(at 162.56 283.21 0)
			(effects
				(font
					(size 1.27 1.27)
					(thickness 0.15)
				)
				(justify left bottom)
				(hide yes)
			)
		)
		(property "Description" ""
			(at 153.67 270.51 0)
			(effects
				(font
					(size 1.27 1.27)
				)
				(hide yes)
			)
		)
		(property "Author" "Antmicro"
			(at 162.56 278.13 0)
			(effects
				(font
					(size 1.27 1.27)
					(thickness 0.15)
				)
				(justify left bottom)
				(hide yes)
			)
		)
		(property "License" "Apache-2.0"
			(at 162.56 280.67 0)
			(effects
				(font
					(size 1.27 1.27)
					(thickness 0.15)
				)
				(justify left bottom)
				(hide yes)
			)
		)
		(pin "1"
		)
		(instances
			(project "jetson-orin-baseboard"
				(path ""
					(reference "#PWR08")
					(unit 1)
				)
			)
		)
	)
	(symbol
		(lib_id "antmicropower:GND")
		(at 242.57 154.94 0)
		(unit 1)
		(exclude_from_sim no)
		(in_bom yes)
		(on_board yes)
		(dnp no)
		(property "Reference" "#PWR0343"
			(at 242.57 161.29 0)
			(effects
				(font
					(size 1.27 1.27)
				)
				(justify left bottom)
				(hide yes)
			)
		)
		(property "Value" "GND"
			(at 242.57 158.75 0)
			(effects
				(font
					(size 1.27 1.27)
					(thickness 0.15)
				)
			)
		)
		(property "Footprint" ""
			(at 251.46 162.56 0)
			(effects
				(font
					(size 1.27 1.27)
					(thickness 0.15)
				)
				(justify left bottom)
				(hide yes)
			)
		)
		(property "Datasheet" ""
			(at 251.46 167.64 0)
			(effects
				(font
					(size 1.27 1.27)
					(thickness 0.15)
				)
				(justify left bottom)
				(hide yes)
			)
		)
		(property "Description" ""
			(at 242.57 154.94 0)
			(effects
				(font
					(size 1.27 1.27)
				)
				(hide yes)
			)
		)
		(property "Author" "Antmicro"
			(at 251.46 162.56 0)
			(effects
				(font
					(size 1.27 1.27)
					(thickness 0.15)
				)
				(justify left bottom)
				(hide yes)
			)
		)
		(property "License" "Apache-2.0"
			(at 251.46 165.1 0)
			(effects
				(font
					(size 1.27 1.27)
					(thickness 0.15)
				)
				(justify left bottom)
				(hide yes)
			)
		)
		(pin "1"
		)
		(instances
			(project "jetson-orin-baseboard"
				(path ""
					(reference "#PWR0343")
					(unit 1)
				)
			)
		)
	)
	(symbol
		(lib_id "antmicropower:GND")
		(at 233.68 154.94 0)
		(unit 1)
		(exclude_from_sim no)
		(in_bom yes)
		(on_board yes)
		(dnp no)
		(property "Reference" "#PWR0342"
			(at 233.68 161.29 0)
			(effects
				(font
					(size 1.27 1.27)
				)
				(justify left bottom)
				(hide yes)
			)
		)
		(property "Value" "GND"
			(at 233.68 158.75 0)
			(effects
				(font
					(size 1.27 1.27)
					(thickness 0.15)
				)
			)
		)
		(property "Footprint" ""
			(at 242.57 162.56 0)
			(effects
				(font
					(size 1.27 1.27)
					(thickness 0.15)
				)
				(justify left bottom)
				(hide yes)
			)
		)
		(property "Datasheet" ""
			(at 242.57 167.64 0)
			(effects
				(font
					(size 1.27 1.27)
					(thickness 0.15)
				)
				(justify left bottom)
				(hide yes)
			)
		)
		(property "Description" ""
			(at 233.68 154.94 0)
			(effects
				(font
					(size 1.27 1.27)
				)
				(hide yes)
			)
		)
		(property "Author" "Antmicro"
			(at 242.57 162.56 0)
			(effects
				(font
					(size 1.27 1.27)
					(thickness 0.15)
				)
				(justify left bottom)
				(hide yes)
			)
		)
		(property "License" "Apache-2.0"
			(at 242.57 165.1 0)
			(effects
				(font
					(size 1.27 1.27)
					(thickness 0.15)
				)
				(justify left bottom)
				(hide yes)
			)
		)
		(pin "1"
		)
		(instances
			(project "jetson-orin-baseboard"
				(path ""
					(reference "#PWR0342")
					(unit 1)
				)
			)
		)
	)
	(symbol
		(lib_id "antmicropower:PWR_FLAG")
		(at 393.7 116.84 0)
		(unit 1)
		(exclude_from_sim no)
		(in_bom yes)
		(on_board yes)
		(dnp no)
		(property "Reference" "#FLG05"
			(at 393.7 114.935 0)
			(effects
				(font
					(size 1.27 1.27)
				)
				(hide yes)
			)
		)
		(property "Value" "PWR_FLAG"
			(at 393.7 113.03 0)
			(effects
				(font
					(size 1.27 1.27)
				)
			)
		)
		(property "Footprint" ""
			(at 393.7 116.84 0)
			(effects
				(font
					(size 1.27 1.27)
				)
				(hide yes)
			)
		)
		(property "Datasheet" ""
			(at 393.7 116.84 0)
			(effects
				(font
					(size 1.27 1.27)
				)
				(hide yes)
			)
		)
		(property "Description" ""
			(at 393.7 116.84 0)
			(effects
				(font
					(size 1.27 1.27)
				)
				(hide yes)
			)
		)
		(pin "1"
		)
		(instances
			(project "jetson-orin-baseboard"
				(path ""
					(reference "#FLG05")
					(unit 1)
				)
			)
		)
	)
	(symbol
		(lib_id "antmicropower:GND")
		(at 246.38 57.15 0)
		(unit 1)
		(exclude_from_sim no)
		(in_bom yes)
		(on_board yes)
		(dnp no)
		(property "Reference" "#PWR0268"
			(at 246.38 63.5 0)
			(effects
				(font
					(size 1.27 1.27)
				)
				(justify left bottom)
				(hide yes)
			)
		)
		(property "Value" "GND"
			(at 246.38 60.96 0)
			(effects
				(font
					(size 1.27 1.27)
					(thickness 0.15)
				)
			)
		)
		(property "Footprint" ""
			(at 255.27 64.77 0)
			(effects
				(font
					(size 1.27 1.27)
					(thickness 0.15)
				)
				(justify left bottom)
				(hide yes)
			)
		)
		(property "Datasheet" ""
			(at 255.27 69.85 0)
			(effects
				(font
					(size 1.27 1.27)
					(thickness 0.15)
				)
				(justify left bottom)
				(hide yes)
			)
		)
		(property "Description" ""
			(at 246.38 57.15 0)
			(effects
				(font
					(size 1.27 1.27)
				)
				(hide yes)
			)
		)
		(property "Author" "Antmicro"
			(at 255.27 64.77 0)
			(effects
				(font
					(size 1.27 1.27)
					(thickness 0.15)
				)
				(justify left bottom)
				(hide yes)
			)
		)
		(property "License" "Apache-2.0"
			(at 255.27 67.31 0)
			(effects
				(font
					(size 1.27 1.27)
					(thickness 0.15)
				)
				(justify left bottom)
				(hide yes)
			)
		)
		(pin "1"
		)
		(instances
			(project "jetson-orin-baseboard"
				(path ""
					(reference "#PWR0268")
					(unit 1)
				)
			)
		)
	)
	(symbol
		(lib_id "antmicropower:GND")
		(at 233.68 213.36 0)
		(unit 1)
		(exclude_from_sim no)
		(in_bom yes)
		(on_board yes)
		(dnp no)
		(property "Reference" "#PWR0334"
			(at 233.68 219.71 0)
			(effects
				(font
					(size 1.27 1.27)
				)
				(justify left bottom)
				(hide yes)
			)
		)
		(property "Value" "GND"
			(at 233.68 217.17 0)
			(effects
				(font
					(size 1.27 1.27)
					(thickness 0.15)
				)
			)
		)
		(property "Footprint" ""
			(at 242.57 220.98 0)
			(effects
				(font
					(size 1.27 1.27)
					(thickness 0.15)
				)
				(justify left bottom)
				(hide yes)
			)
		)
		(property "Datasheet" ""
			(at 242.57 226.06 0)
			(effects
				(font
					(size 1.27 1.27)
					(thickness 0.15)
				)
				(justify left bottom)
				(hide yes)
			)
		)
		(property "Description" ""
			(at 233.68 213.36 0)
			(effects
				(font
					(size 1.27 1.27)
				)
				(hide yes)
			)
		)
		(property "Author" "Antmicro"
			(at 242.57 220.98 0)
			(effects
				(font
					(size 1.27 1.27)
					(thickness 0.15)
				)
				(justify left bottom)
				(hide yes)
			)
		)
		(property "License" "Apache-2.0"
			(at 242.57 223.52 0)
			(effects
				(font
					(size 1.27 1.27)
					(thickness 0.15)
				)
				(justify left bottom)
				(hide yes)
			)
		)
		(pin "1"
		)
		(instances
			(project "jetson-orin-baseboard"
				(path ""
					(reference "#PWR0334")
					(unit 1)
				)
			)
		)
	)
	(symbol
		(lib_id "antmicroResistors0402:R_10k_0402")
		(at 73.66 152.4 90)
		(unit 1)
		(exclude_from_sim no)
		(in_bom yes)
		(on_board yes)
		(dnp no)
		(property "Reference" "R254"
			(at 74.93 148.59 90)
			(effects
				(font
					(size 1.27 1.27)
				)
				(justify right)
			)
		)
		(property "Value" "R_10k_0402"
			(at 86.36 132.08 0)
			(effects
				(font
					(size 1.27 1.27)
					(thickness 0.15)
				)
				(justify left bottom)
				(hide yes)
			)
		)
		(property "Footprint" "antmicro-footprints:R_0402_1005Metric"
			(at 88.9 132.08 0)
			(effects
				(font
					(size 1.27 1.27)
					(thickness 0.15)
				)
				(justify left bottom)
				(hide yes)
			)
		)
		(property "Datasheet" "https://www.bourns.com/docs/product-datasheets/cr.pdf"
			(at 91.44 132.08 0)
			(effects
				(font
					(size 1.27 1.27)
					(thickness 0.15)
				)
				(justify left bottom)
				(hide yes)
			)
		)
		(property "Description" ""
			(at 73.66 152.4 0)
			(effects
				(font
					(size 1.27 1.27)
				)
				(hide yes)
			)
		)
		(property "Manufacturer" "Bourns"
			(at 96.52 132.08 0)
			(effects
				(font
					(size 1.27 1.27)
					(thickness 0.15)
				)
				(justify left bottom)
				(hide yes)
			)
		)
		(property "MPN" "CR0402-FX-1002GLF"
			(at 93.98 132.08 0)
			(effects
				(font
					(size 1.27 1.27)
					(thickness 0.15)
				)
				(justify left bottom)
				(hide yes)
			)
		)
		(property "Val" "10k"
			(at 74.93 151.13 90)
			(effects
				(font
					(size 1.27 1.27)
					(thickness 0.15)
				)
				(justify right)
			)
		)
		(property "License" "Apache-2.0"
			(at 99.06 132.08 0)
			(effects
				(font
					(size 1.27 1.27)
					(thickness 0.15)
				)
				(justify left bottom)
				(hide yes)
			)
		)
		(property "Author" "Antmicro"
			(at 101.6 132.08 0)
			(effects
				(font
					(size 1.27 1.27)
					(thickness 0.15)
				)
				(justify left bottom)
				(hide yes)
			)
		)
		(property "Tolerance" "1%"
			(at 83.82 132.08 0)
			(effects
				(font
					(size 1.27 1.27)
				)
				(justify left bottom)
				(hide yes)
			)
		)
		(pin "1"
		)
		(pin "2"
		)
		(instances
			(project "jetson-orin-baseboard"
				(path ""
					(reference "R254")
					(unit 1)
				)
			)
		)
	)
	(symbol
		(lib_id "antmicroTransistorsFETsMOSFETsSingle:SSM3J332R")
		(at 63.5 172.72 90)
		(unit 1)
		(exclude_from_sim no)
		(in_bom yes)
		(on_board yes)
		(dnp no)
		(fields_autoplaced yes)
		(property "Reference" "Q16"
			(at 60.96 158.75 90)
			(effects
				(font
					(size 1.27 1.27)
				)
			)
		)
		(property "Value" "SSM3J332R"
			(at 66.04 158.75 0)
			(effects
				(font
					(size 1.27 1.27)
					(thickness 0.15)
				)
				(justify left bottom)
				(hide yes)
			)
		)
		(property "Footprint" "antmicro-footprints:SOT-23-3"
			(at 68.58 158.75 0)
			(effects
				(font
					(size 1.27 1.27)
					(thickness 0.15)
				)
				(justify left bottom)
				(hide yes)
			)
		)
		(property "Datasheet" "https://www.mouser.com/datasheet/2/408/SSM3J332R_datasheet_en_20181015-1150575.pdf"
			(at 71.12 158.75 0)
			(effects
				(font
					(size 1.27 1.27)
					(thickness 0.15)
				)
				(justify left bottom)
				(hide yes)
			)
		)
		(property "Description" ""
			(at 63.5 172.72 0)
			(effects
				(font
					(size 1.27 1.27)
				)
				(hide yes)
			)
		)
		(property "MPN" "SSM3J332R,LF"
			(at 60.96 161.29 90)
			(effects
				(font
					(size 1.27 1.27)
					(thickness 0.15)
				)
			)
		)
		(property "Manufacturer" "Toshiba"
			(at 76.2 158.75 0)
			(effects
				(font
					(size 1.27 1.27)
					(thickness 0.15)
				)
				(justify left bottom)
				(hide yes)
			)
		)
		(property "Author" "Antmicro"
			(at 78.74 158.75 0)
			(effects
				(font
					(size 1.27 1.27)
					(thickness 0.15)
				)
				(justify left bottom)
				(hide yes)
			)
		)
		(property "License" "Apache-2.0"
			(at 81.28 158.75 0)
			(effects
				(font
					(size 1.27 1.27)
					(thickness 0.15)
				)
				(justify left bottom)
				(hide yes)
			)
		)
		(pin "1"
		)
		(pin "2"
		)
		(pin "3"
		)
		(instances
			(project "jetson-orin-baseboard"
				(path ""
					(reference "Q16")
					(unit 1)
				)
			)
		)
	)
	(symbol
		(lib_id "antmicroResistors0402:R_0R_0402")
		(at 234.95 181.61 0)
		(unit 1)
		(exclude_from_sim no)
		(in_bom yes)
		(on_board yes)
		(dnp no)
		(property "Reference" "R264"
			(at 237.49 176.53 0)
			(effects
				(font
					(size 1.27 1.27)
				)
			)
		)
		(property "Value" "R_0R_0402"
			(at 255.27 194.31 0)
			(effects
				(font
					(size 1.27 1.27)
					(thickness 0.15)
				)
				(justify left bottom)
				(hide yes)
			)
		)
		(property "Footprint" "antmicro-footprints:R_0402_1005Metric"
			(at 255.27 196.85 0)
			(effects
				(font
					(size 1.27 1.27)
					(thickness 0.15)
				)
				(justify left bottom)
				(hide yes)
			)
		)
		(property "Datasheet" "https://industrial.panasonic.com/cdbs/www-data/pdf/RDA0000/AOA0000C301.pdf"
			(at 255.27 199.39 0)
			(effects
				(font
					(size 1.27 1.27)
					(thickness 0.15)
				)
				(justify left bottom)
				(hide yes)
			)
		)
		(property "Description" ""
			(at 234.95 181.61 0)
			(effects
				(font
					(size 1.27 1.27)
				)
				(hide yes)
			)
		)
		(property "Manufacturer" "Panasonic"
			(at 255.27 204.47 0)
			(effects
				(font
					(size 1.27 1.27)
					(thickness 0.15)
				)
				(justify left bottom)
				(hide yes)
			)
		)
		(property "MPN" "ERJ2GE0R00X"
			(at 255.27 201.93 0)
			(effects
				(font
					(size 1.27 1.27)
					(thickness 0.15)
				)
				(justify left bottom)
				(hide yes)
			)
		)
		(property "Val" "0R"
			(at 237.49 179.07 0)
			(effects
				(font
					(size 1.27 1.27)
					(thickness 0.15)
				)
			)
		)
		(property "License" "Apache-2.0"
			(at 255.27 207.01 0)
			(effects
				(font
					(size 1.27 1.27)
					(thickness 0.15)
				)
				(justify left bottom)
				(hide yes)
			)
		)
		(property "Author" "Antmicro"
			(at 255.27 209.55 0)
			(effects
				(font
					(size 1.27 1.27)
					(thickness 0.15)
				)
				(justify left bottom)
				(hide yes)
			)
		)
		(property "Tolerance" "~"
			(at 255.27 191.77 0)
			(effects
				(font
					(size 1.27 1.27)
				)
				(justify left bottom)
				(hide yes)
			)
		)
		(property "Current" "1A"
			(at 255.27 212.09 0)
			(effects
				(font
					(size 1.27 1.27)
					(thickness 0.15)
				)
				(justify left bottom)
				(hide yes)
			)
		)
		(pin "1"
		)
		(pin "2"
		)
		(instances
			(project "jetson-orin-baseboard"
				(path ""
					(reference "R264")
					(unit 1)
				)
			)
		)
	)
	(symbol
		(lib_id "antmicropower:GND")
		(at 81.28 63.5 0)
		(unit 1)
		(exclude_from_sim no)
		(in_bom yes)
		(on_board yes)
		(dnp no)
		(property "Reference" "#PWR0258"
			(at 81.28 69.85 0)
			(effects
				(font
					(size 1.27 1.27)
				)
				(justify left bottom)
				(hide yes)
			)
		)
		(property "Value" "GND"
			(at 81.28 67.31 0)
			(effects
				(font
					(size 1.27 1.27)
					(thickness 0.15)
				)
			)
		)
		(property "Footprint" ""
			(at 90.17 71.12 0)
			(effects
				(font
					(size 1.27 1.27)
					(thickness 0.15)
				)
				(justify left bottom)
				(hide yes)
			)
		)
		(property "Datasheet" ""
			(at 90.17 76.2 0)
			(effects
				(font
					(size 1.27 1.27)
					(thickness 0.15)
				)
				(justify left bottom)
				(hide yes)
			)
		)
		(property "Description" ""
			(at 81.28 63.5 0)
			(effects
				(font
					(size 1.27 1.27)
				)
				(hide yes)
			)
		)
		(property "Author" "Antmicro"
			(at 90.17 71.12 0)
			(effects
				(font
					(size 1.27 1.27)
					(thickness 0.15)
				)
				(justify left bottom)
				(hide yes)
			)
		)
		(property "License" "Apache-2.0"
			(at 90.17 73.66 0)
			(effects
				(font
					(size 1.27 1.27)
					(thickness 0.15)
				)
				(justify left bottom)
				(hide yes)
			)
		)
		(pin "1"
		)
		(instances
			(project "jetson-orin-baseboard"
				(path ""
					(reference "#PWR0258")
					(unit 1)
				)
			)
		)
	)
	(symbol
		(lib_id "antmicroResistors0402:R_0R_0402")
		(at 194.31 49.53 0)
		(unit 1)
		(exclude_from_sim no)
		(in_bom yes)
		(on_board yes)
		(dnp no)
		(property "Reference" "R260"
			(at 199.39 48.895 0)
			(effects
				(font
					(size 1.27 1.27)
				)
				(justify left bottom)
			)
		)
		(property "Value" "R_0R_0402"
			(at 214.63 62.23 0)
			(effects
				(font
					(size 1.27 1.27)
					(thickness 0.15)
				)
				(justify left bottom)
				(hide yes)
			)
		)
		(property "Footprint" "antmicro-footprints:R_0402_1005Metric"
			(at 214.63 64.77 0)
			(effects
				(font
					(size 1.27 1.27)
					(thickness 0.15)
				)
				(justify left bottom)
				(hide yes)
			)
		)
		(property "Datasheet" "https://industrial.panasonic.com/cdbs/www-data/pdf/RDA0000/AOA0000C301.pdf"
			(at 214.63 67.31 0)
			(effects
				(font
					(size 1.27 1.27)
					(thickness 0.15)
				)
				(justify left bottom)
				(hide yes)
			)
		)
		(property "Description" ""
			(at 194.31 49.53 0)
			(effects
				(font
					(size 1.27 1.27)
				)
				(hide yes)
			)
		)
		(property "Manufacturer" "Panasonic"
			(at 214.63 72.39 0)
			(effects
				(font
					(size 1.27 1.27)
					(thickness 0.15)
				)
				(justify left bottom)
				(hide yes)
			)
		)
		(property "MPN" "ERJ2GE0R00X"
			(at 214.63 69.85 0)
			(effects
				(font
					(size 1.27 1.27)
					(thickness 0.15)
				)
				(justify left bottom)
				(hide yes)
			)
		)
		(property "Val" "0R"
			(at 191.77 48.895 0)
			(effects
				(font
					(size 1.27 1.27)
					(thickness 0.15)
				)
				(justify left bottom)
			)
		)
		(property "License" "Apache-2.0"
			(at 214.63 74.93 0)
			(effects
				(font
					(size 1.27 1.27)
					(thickness 0.15)
				)
				(justify left bottom)
				(hide yes)
			)
		)
		(property "Author" "Antmicro"
			(at 214.63 77.47 0)
			(effects
				(font
					(size 1.27 1.27)
					(thickness 0.15)
				)
				(justify left bottom)
				(hide yes)
			)
		)
		(property "Tolerance" "~"
			(at 214.63 59.69 0)
			(effects
				(font
					(size 1.27 1.27)
				)
				(justify left bottom)
				(hide yes)
			)
		)
		(property "Current" "1A"
			(at 214.63 80.01 0)
			(effects
				(font
					(size 1.27 1.27)
					(thickness 0.15)
				)
				(justify left bottom)
				(hide yes)
			)
		)
		(pin "1"
		)
		(pin "2"
		)
		(instances
			(project "jetson-orin-baseboard"
				(path ""
					(reference "R260")
					(unit 1)
				)
			)
		)
	)
	(symbol
		(lib_id "antmicroCapacitors0402:C_10u_0402")
		(at 355.6 36.83 90)
		(unit 1)
		(exclude_from_sim no)
		(in_bom yes)
		(on_board yes)
		(dnp no)
		(property "Reference" "C137"
			(at 357.505 33.02 90)
			(effects
				(font
					(size 1.27 1.27)
					(thickness 0.15)
				)
				(justify right)
			)
		)
		(property "Value" "C_10u_0402"
			(at 365.76 16.51 0)
			(effects
				(font
					(size 1.27 1.27)
					(thickness 0.15)
				)
				(justify left bottom)
				(hide yes)
			)
		)
		(property "Footprint" "antmicro-footprints:C_0402_1005Metric"
			(at 368.3 16.51 0)
			(effects
				(font
					(size 1.27 1.27)
					(thickness 0.15)
				)
				(justify left bottom)
				(hide yes)
			)
		)
		(property "Datasheet" "https://www.yageo.com/en/Chart/Download/pdf/CC0402MRX5R5BB106"
			(at 370.84 16.51 0)
			(effects
				(font
					(size 1.27 1.27)
					(thickness 0.15)
				)
				(justify left bottom)
				(hide yes)
			)
		)
		(property "Description" ""
			(at 355.6 36.83 0)
			(effects
				(font
					(size 1.27 1.27)
				)
				(hide yes)
			)
		)
		(property "MPN" "CC0402MRX5R5BB106"
			(at 373.38 16.51 0)
			(effects
				(font
					(size 1.27 1.27)
					(thickness 0.15)
				)
				(justify left bottom)
				(hide yes)
			)
		)
		(property "Manufacturer" "YAGEO"
			(at 375.92 16.51 0)
			(effects
				(font
					(size 1.27 1.27)
					(thickness 0.15)
				)
				(justify left bottom)
				(hide yes)
			)
		)
		(property "License" "Apache-2.0"
			(at 378.46 16.51 0)
			(effects
				(font
					(size 1.27 1.27)
					(thickness 0.15)
				)
				(justify left bottom)
				(hide yes)
			)
		)
		(property "Author" "Antmicro"
			(at 381 16.51 0)
			(effects
				(font
					(size 1.27 1.27)
					(thickness 0.15)
				)
				(justify left bottom)
				(hide yes)
			)
		)
		(property "Val" "10u"
			(at 357.505 35.56 90)
			(effects
				(font
					(size 1.27 1.27)
					(thickness 0.15)
				)
				(justify right)
			)
		)
		(property "Voltage" ""
			(at 383.54 16.51 0)
			(effects
				(font
					(size 1.27 1.27)
				)
				(justify left bottom)
				(hide yes)
			)
		)
		(property "Dielectric" ""
			(at 386.08 16.51 0)
			(effects
				(font
					(size 1.27 1.27)
				)
				(justify left bottom)
				(hide yes)
			)
		)
		(pin "1"
		)
		(pin "2"
		)
		(instances
			(project "jetson-orin-baseboard"
				(path ""
					(reference "C137")
					(unit 1)
				)
			)
		)
	)
	(symbol
		(lib_id "antmicropower:GND")
		(at 162.56 270.51 0)
		(unit 1)
		(exclude_from_sim no)
		(in_bom yes)
		(on_board yes)
		(dnp no)
		(fields_autoplaced yes)
		(property "Reference" "#PWR0377"
			(at 162.56 276.86 0)
			(effects
				(font
					(size 1.27 1.27)
				)
				(justify left bottom)
				(hide yes)
			)
		)
		(property "Value" "GND"
			(at 162.56 274.32 0)
			(effects
				(font
					(size 1.27 1.27)
					(thickness 0.15)
				)
			)
		)
		(property "Footprint" ""
			(at 171.45 278.13 0)
			(effects
				(font
					(size 1.27 1.27)
					(thickness 0.15)
				)
				(justify left bottom)
				(hide yes)
			)
		)
		(property "Datasheet" ""
			(at 171.45 283.21 0)
			(effects
				(font
					(size 1.27 1.27)
					(thickness 0.15)
				)
				(justify left bottom)
				(hide yes)
			)
		)
		(property "Description" ""
			(at 162.56 270.51 0)
			(effects
				(font
					(size 1.27 1.27)
				)
				(hide yes)
			)
		)
		(property "Author" "Antmicro"
			(at 171.45 278.13 0)
			(effects
				(font
					(size 1.27 1.27)
					(thickness 0.15)
				)
				(justify left bottom)
				(hide yes)
			)
		)
		(property "License" "Apache-2.0"
			(at 171.45 280.67 0)
			(effects
				(font
					(size 1.27 1.27)
					(thickness 0.15)
				)
				(justify left bottom)
				(hide yes)
			)
		)
		(pin "1"
		)
		(instances
			(project "jetson-orin-baseboard"
				(path ""
					(reference "#PWR0377")
					(unit 1)
				)
			)
		)
	)
	(symbol
		(lib_id "antmicroResistors0402:R_73k2_0402")
		(at 302.26 140.97 90)
		(unit 1)
		(exclude_from_sim no)
		(in_bom yes)
		(on_board yes)
		(dnp no)
		(property "Reference" "R170"
			(at 303.53 137.16 90)
			(effects
				(font
					(size 1.27 1.27)
					(thickness 0.15)
				)
				(justify right)
			)
		)
		(property "Value" "R_73k2_0402"
			(at 314.96 120.65 0)
			(effects
				(font
					(size 1.27 1.27)
					(thickness 0.15)
				)
				(justify left bottom)
				(hide yes)
			)
		)
		(property "Footprint" "antmicro-footprints:R_0402_1005Metric"
			(at 317.5 120.65 0)
			(effects
				(font
					(size 1.27 1.27)
					(thickness 0.15)
				)
				(justify left bottom)
				(hide yes)
			)
		)
		(property "Datasheet" "https://www.bourns.com/docs/product-datasheets/cr.pdf"
			(at 320.04 120.65 0)
			(effects
				(font
					(size 1.27 1.27)
					(thickness 0.15)
				)
				(justify left bottom)
				(hide yes)
			)
		)
		(property "Description" ""
			(at 302.26 140.97 0)
			(effects
				(font
					(size 1.27 1.27)
				)
				(hide yes)
			)
		)
		(property "MPN" "CR0402-FX-7322GLF"
			(at 322.58 120.65 0)
			(effects
				(font
					(size 1.27 1.27)
					(thickness 0.15)
				)
				(justify left bottom)
				(hide yes)
			)
		)
		(property "Manufacturer" "Bourns"
			(at 325.12 120.65 0)
			(effects
				(font
					(size 1.27 1.27)
					(thickness 0.15)
				)
				(justify left bottom)
				(hide yes)
			)
		)
		(property "License" "Apache-2.0"
			(at 327.66 120.65 0)
			(effects
				(font
					(size 1.27 1.27)
					(thickness 0.15)
				)
				(justify left bottom)
				(hide yes)
			)
		)
		(property "Author" "Antmicro"
			(at 330.2 120.65 0)
			(effects
				(font
					(size 1.27 1.27)
					(thickness 0.15)
				)
				(justify left bottom)
				(hide yes)
			)
		)
		(property "Val" "73k2"
			(at 303.53 139.7 90)
			(effects
				(font
					(size 1.27 1.27)
					(thickness 0.15)
				)
				(justify right)
			)
		)
		(property "Tolerance" "1%"
			(at 312.42 120.65 0)
			(effects
				(font
					(size 1.27 1.27)
				)
				(justify left bottom)
				(hide yes)
			)
		)
		(pin "2"
		)
		(pin "1"
		)
		(instances
			(project "jetson-orin-baseboard"
				(path ""
					(reference "R170")
					(unit 1)
				)
			)
		)
	)
	(symbol
		(lib_id "antmicropower:GND")
		(at 38.1 125.73 0)
		(unit 1)
		(exclude_from_sim no)
		(in_bom yes)
		(on_board yes)
		(dnp no)
		(property "Reference" "#PWR0283"
			(at 38.1 132.08 0)
			(effects
				(font
					(size 1.27 1.27)
				)
				(justify left bottom)
				(hide yes)
			)
		)
		(property "Value" "GND"
			(at 38.1 129.54 0)
			(effects
				(font
					(size 1.27 1.27)
					(thickness 0.15)
				)
			)
		)
		(property "Footprint" ""
			(at 46.99 133.35 0)
			(effects
				(font
					(size 1.27 1.27)
					(thickness 0.15)
				)
				(justify left bottom)
				(hide yes)
			)
		)
		(property "Datasheet" ""
			(at 46.99 138.43 0)
			(effects
				(font
					(size 1.27 1.27)
					(thickness 0.15)
				)
				(justify left bottom)
				(hide yes)
			)
		)
		(property "Description" ""
			(at 38.1 125.73 0)
			(effects
				(font
					(size 1.27 1.27)
				)
				(hide yes)
			)
		)
		(property "Author" "Antmicro"
			(at 46.99 133.35 0)
			(effects
				(font
					(size 1.27 1.27)
					(thickness 0.15)
				)
				(justify left bottom)
				(hide yes)
			)
		)
		(property "License" "Apache-2.0"
			(at 46.99 135.89 0)
			(effects
				(font
					(size 1.27 1.27)
					(thickness 0.15)
				)
				(justify left bottom)
				(hide yes)
			)
		)
		(pin "1"
		)
		(instances
			(project "jetson-orin-baseboard"
				(path ""
					(reference "#PWR0283")
					(unit 1)
				)
			)
		)
	)
	(symbol
		(lib_id "antmicroLogicGatesandInverters:74LVC1G175_SOT457")
		(at 175.26 49.53 0)
		(unit 1)
		(exclude_from_sim no)
		(in_bom yes)
		(on_board yes)
		(dnp no)
		(property "Reference" "U38"
			(at 184.15 42.545 0)
			(effects
				(font
					(size 1.27 1.27)
				)
				(justify left)
			)
		)
		(property "Value" "74LVC1G175_SOT457"
			(at 205.74 57.15 0)
			(effects
				(font
					(size 1.27 1.27)
					(thickness 0.15)
				)
				(justify left bottom)
				(hide yes)
			)
		)
		(property "Footprint" "antmicro-footprints:SOT-23-6"
			(at 205.74 59.69 0)
			(effects
				(font
					(size 1.27 1.27)
					(thickness 0.15)
				)
				(justify left bottom)
				(hide yes)
			)
		)
		(property "Datasheet" "https://www.mouser.com/datasheet/2/916/74LVC1G175-1480578.pdf"
			(at 205.74 62.23 0)
			(effects
				(font
					(size 1.27 1.27)
					(thickness 0.15)
				)
				(justify left bottom)
				(hide yes)
			)
		)
		(property "Description" ""
			(at 175.26 49.53 0)
			(effects
				(font
					(size 1.27 1.27)
				)
				(hide yes)
			)
		)
		(property "MPN" "74LVC1G175GV,125"
			(at 184.15 45.085 0)
			(effects
				(font
					(size 1.27 1.27)
					(thickness 0.15)
				)
				(justify left)
			)
		)
		(property "Manufacturer" "Nexperia"
			(at 205.74 67.31 0)
			(effects
				(font
					(size 1.27 1.27)
					(thickness 0.15)
				)
				(justify left bottom)
				(hide yes)
			)
		)
		(property "Author" "Antmicro"
			(at 205.74 69.85 0)
			(effects
				(font
					(size 1.27 1.27)
					(thickness 0.15)
				)
				(justify left bottom)
				(hide yes)
			)
		)
		(property "License" "Apache-2.0"
			(at 205.74 72.39 0)
			(effects
				(font
					(size 1.27 1.27)
					(thickness 0.15)
				)
				(justify left bottom)
				(hide yes)
			)
		)
		(pin "1"
		)
		(pin "2"
		)
		(pin "3"
		)
		(pin "4"
		)
		(pin "5"
		)
		(pin "6"
		)
		(instances
			(project "jetson-orin-baseboard"
				(path ""
					(reference "U38")
					(unit 1)
				)
			)
		)
	)
	(symbol
		(lib_id "antmicroResistors0603:R_0R_22.4A_0603")
		(at 344.17 134.62 0)
		(unit 1)
		(exclude_from_sim no)
		(in_bom yes)
		(on_board yes)
		(dnp no)
		(property "Reference" "R172"
			(at 349.25 133.985 0)
			(effects
				(font
					(size 1.27 1.27)
				)
				(justify left bottom)
			)
		)
		(property "Value" "R_0R_22.4A_0603"
			(at 346.71 125.73 0)
			(effects
				(font
					(size 1.27 1.27)
					(thickness 0.15)
				)
				(hide yes)
			)
		)
		(property "Footprint" "antmicro-footprints:R_0603_1608Metric"
			(at 359.41 144.78 0)
			(effects
				(font
					(size 1.27 1.27)
					(thickness 0.15)
				)
				(justify left bottom)
				(hide yes)
			)
		)
		(property "Datasheet" "https://fscdn.rohm.com/en/products/databook/datasheet/passive/resistor/chip_resistor/pmr-jpw-e.pdf"
			(at 359.41 147.32 0)
			(effects
				(font
					(size 1.27 1.27)
					(thickness 0.15)
				)
				(justify left bottom)
				(hide yes)
			)
		)
		(property "Description" ""
			(at 344.17 134.62 0)
			(effects
				(font
					(size 1.27 1.27)
				)
				(hide yes)
			)
		)
		(property "Manufacturer" "ROHM Semiconductor"
			(at 359.41 152.4 0)
			(effects
				(font
					(size 1.27 1.27)
					(thickness 0.15)
				)
				(justify left bottom)
				(hide yes)
			)
		)
		(property "MPN" "PMR03EZPJ000"
			(at 359.41 149.86 0)
			(effects
				(font
					(size 1.27 1.27)
					(thickness 0.15)
				)
				(justify left bottom)
				(hide yes)
			)
		)
		(property "Val" "0R"
			(at 341.63 133.985 0)
			(effects
				(font
					(size 1.27 1.27)
					(thickness 0.15)
				)
				(justify left bottom)
			)
		)
		(property "Author" "Antmicro"
			(at 359.41 157.48 0)
			(effects
				(font
					(size 1.27 1.27)
					(thickness 0.15)
				)
				(justify left bottom)
				(hide yes)
			)
		)
		(property "License" "Apache-2.0"
			(at 359.41 160.02 0)
			(effects
				(font
					(size 1.27 1.27)
					(thickness 0.15)
				)
				(justify left bottom)
				(hide yes)
			)
		)
		(property "Max. Curr." "22.4A"
			(at 346.71 136.525 0)
			(effects
				(font
					(size 1.27 1.27)
					(thickness 0.15)
				)
			)
		)
		(property "Tolerance" "template_tolerance"
			(at 364.49 144.78 0)
			(effects
				(font
					(size 1.27 1.27)
				)
				(justify left bottom)
				(hide yes)
			)
		)
		(pin "1"
		)
		(pin "2"
		)
		(instances
			(project "jetson-orin-baseboard"
				(path ""
					(reference "R172")
					(unit 1)
				)
			)
		)
	)
	(symbol
		(lib_id "antmicroResistors0402:R_10k_0402")
		(at 302.26 207.01 90)
		(unit 1)
		(exclude_from_sim no)
		(in_bom yes)
		(on_board yes)
		(dnp no)
		(property "Reference" "R238"
			(at 303.53 203.2 90)
			(effects
				(font
					(size 1.27 1.27)
					(thickness 0.15)
				)
				(justify right)
			)
		)
		(property "Value" "R_10k_0402"
			(at 314.96 186.69 0)
			(effects
				(font
					(size 1.27 1.27)
					(thickness 0.15)
				)
				(justify left bottom)
				(hide yes)
			)
		)
		(property "Footprint" "antmicro-footprints:R_0402_1005Metric"
			(at 317.5 186.69 0)
			(effects
				(font
					(size 1.27 1.27)
					(thickness 0.15)
				)
				(justify left bottom)
				(hide yes)
			)
		)
		(property "Datasheet" "https://www.bourns.com/docs/product-datasheets/cr.pdf"
			(at 320.04 186.69 0)
			(effects
				(font
					(size 1.27 1.27)
					(thickness 0.15)
				)
				(justify left bottom)
				(hide yes)
			)
		)
		(property "Description" ""
			(at 302.26 207.01 0)
			(effects
				(font
					(size 1.27 1.27)
				)
				(hide yes)
			)
		)
		(property "MPN" "CR0402-FX-1002GLF"
			(at 322.58 186.69 0)
			(effects
				(font
					(size 1.27 1.27)
					(thickness 0.15)
				)
				(justify left bottom)
				(hide yes)
			)
		)
		(property "Manufacturer" "Bourns"
			(at 325.12 186.69 0)
			(effects
				(font
					(size 1.27 1.27)
					(thickness 0.15)
				)
				(justify left bottom)
				(hide yes)
			)
		)
		(property "License" "Apache-2.0"
			(at 327.66 186.69 0)
			(effects
				(font
					(size 1.27 1.27)
					(thickness 0.15)
				)
				(justify left bottom)
				(hide yes)
			)
		)
		(property "Author" "Antmicro"
			(at 330.2 186.69 0)
			(effects
				(font
					(size 1.27 1.27)
					(thickness 0.15)
				)
				(justify left bottom)
				(hide yes)
			)
		)
		(property "Val" "10k"
			(at 303.53 205.74 90)
			(effects
				(font
					(size 1.27 1.27)
					(thickness 0.15)
				)
				(justify right)
			)
		)
		(property "Tolerance" "1%"
			(at 312.42 186.69 0)
			(effects
				(font
					(size 1.27 1.27)
				)
				(justify left bottom)
				(hide yes)
			)
		)
		(pin "2"
		)
		(pin "1"
		)
		(instances
			(project "jetson-orin-baseboard"
				(path ""
					(reference "R238")
					(unit 1)
				)
			)
		)
	)
	(symbol
		(lib_id "antmicroResistors0603:R_0R_22.4A_0603")
		(at 374.65 121.92 0)
		(unit 1)
		(exclude_from_sim no)
		(in_bom no)
		(on_board yes)
		(dnp yes)
		(property "Reference" "R182"
			(at 379.73 121.285 0)
			(effects
				(font
					(size 1.27 1.27)
				)
				(justify left bottom)
			)
		)
		(property "Value" "R_0R_22.4A_0603"
			(at 377.19 110.49 0)
			(effects
				(font
					(size 1.27 1.27)
					(thickness 0.15)
				)
				(hide yes)
			)
		)
		(property "Footprint" "antmicro-footprints:R_0603_1608Metric"
			(at 389.89 132.08 0)
			(effects
				(font
					(size 1.27 1.27)
					(thickness 0.15)
				)
				(justify left bottom)
				(hide yes)
			)
		)
		(property "Datasheet" "https://fscdn.rohm.com/en/products/databook/datasheet/passive/resistor/chip_resistor/pmr-jpw-e.pdf"
			(at 389.89 134.62 0)
			(effects
				(font
					(size 1.27 1.27)
					(thickness 0.15)
				)
				(justify left bottom)
				(hide yes)
			)
		)
		(property "Description" ""
			(at 374.65 121.92 0)
			(effects
				(font
					(size 1.27 1.27)
				)
				(hide yes)
			)
		)
		(property "Manufacturer" "ROHM Semiconductor"
			(at 389.89 139.7 0)
			(effects
				(font
					(size 1.27 1.27)
					(thickness 0.15)
				)
				(justify left bottom)
				(hide yes)
			)
		)
		(property "MPN" "PMR03EZPJ000"
			(at 389.89 137.16 0)
			(effects
				(font
					(size 1.27 1.27)
					(thickness 0.15)
				)
				(justify left bottom)
				(hide yes)
			)
		)
		(property "Val" "0R"
			(at 372.11 121.285 0)
			(effects
				(font
					(size 1.27 1.27)
					(thickness 0.15)
				)
				(justify left bottom)
			)
		)
		(property "Author" "Antmicro"
			(at 389.89 144.78 0)
			(effects
				(font
					(size 1.27 1.27)
					(thickness 0.15)
				)
				(justify left bottom)
				(hide yes)
			)
		)
		(property "License" "Apache-2.0"
			(at 389.89 147.32 0)
			(effects
				(font
					(size 1.27 1.27)
					(thickness 0.15)
				)
				(justify left bottom)
				(hide yes)
			)
		)
		(property "Max. Curr." "22.4A"
			(at 377.19 123.825 0)
			(effects
				(font
					(size 1.27 1.27)
					(thickness 0.15)
				)
			)
		)
		(property "Tolerance" "template_tolerance"
			(at 394.97 132.08 0)
			(effects
				(font
					(size 1.27 1.27)
				)
				(justify left bottom)
				(hide yes)
			)
		)
		(pin "1"
		)
		(pin "2"
		)
		(instances
			(project "jetson-orin-baseboard"
				(path ""
					(reference "R182")
					(unit 1)
				)
			)
		)
	)
	(symbol
		(lib_id "antmicroResistors0603:R_0R_0603")
		(at 373.38 71.12 0)
		(unit 1)
		(exclude_from_sim no)
		(in_bom yes)
		(on_board yes)
		(dnp no)
		(property "Reference" "R276"
			(at 378.46 70.485 0)
			(effects
				(font
					(size 1.27 1.27)
				)
				(justify left bottom)
			)
		)
		(property "Value" "R_0R_0603"
			(at 393.7 83.82 0)
			(effects
				(font
					(size 1.27 1.27)
					(thickness 0.15)
				)
				(justify left bottom)
				(hide yes)
			)
		)
		(property "Footprint" "antmicro-footprints:R_0603_1608Metric"
			(at 393.7 86.36 0)
			(effects
				(font
					(size 1.27 1.27)
					(thickness 0.15)
				)
				(justify left bottom)
				(hide yes)
			)
		)
		(property "Datasheet" "https://www.bourns.com/docs/product-datasheets/cr.pdf?sfvrsn=574d41f6_14"
			(at 393.7 88.9 0)
			(effects
				(font
					(size 1.27 1.27)
					(thickness 0.15)
				)
				(justify left bottom)
				(hide yes)
			)
		)
		(property "Description" ""
			(at 373.38 71.12 0)
			(effects
				(font
					(size 1.27 1.27)
				)
				(hide yes)
			)
		)
		(property "Manufacturer" "Bourns"
			(at 393.7 93.98 0)
			(effects
				(font
					(size 1.27 1.27)
					(thickness 0.15)
				)
				(justify left bottom)
				(hide yes)
			)
		)
		(property "MPN" "CR0603-J/-000ELF"
			(at 393.7 91.44 0)
			(effects
				(font
					(size 1.27 1.27)
					(thickness 0.15)
				)
				(justify left bottom)
				(hide yes)
			)
		)
		(property "Val" "0R"
			(at 370.84 70.485 0)
			(effects
				(font
					(size 1.27 1.27)
					(thickness 0.15)
				)
				(justify left bottom)
			)
		)
		(property "License" "Apache-2.0"
			(at 393.7 96.52 0)
			(effects
				(font
					(size 1.27 1.27)
					(thickness 0.15)
				)
				(justify left bottom)
				(hide yes)
			)
		)
		(property "Author" "Antmicro"
			(at 393.7 99.06 0)
			(effects
				(font
					(size 1.27 1.27)
					(thickness 0.15)
				)
				(justify left bottom)
				(hide yes)
			)
		)
		(property "Tolerance" "~"
			(at 393.7 81.28 0)
			(effects
				(font
					(size 1.27 1.27)
				)
				(justify left bottom)
				(hide yes)
			)
		)
		(property "Current" "1A"
			(at 393.7 101.6 0)
			(effects
				(font
					(size 1.27 1.27)
					(thickness 0.15)
				)
				(justify left bottom)
				(hide yes)
			)
		)
		(pin "1"
		)
		(pin "2"
		)
		(instances
			(project "jetson-orin-baseboard"
				(path ""
					(reference "R276")
					(unit 1)
				)
			)
		)
	)
	(symbol
		(lib_id "antmicroResistors0402:R_200k_0402")
		(at 109.22 39.37 0)
		(unit 1)
		(exclude_from_sim no)
		(in_bom yes)
		(on_board yes)
		(dnp no)
		(property "Reference" "R258"
			(at 114.3 38.735 0)
			(effects
				(font
					(size 1.27 1.27)
				)
				(justify left bottom)
			)
		)
		(property "Value" "R_200k_0402"
			(at 129.54 52.07 0)
			(effects
				(font
					(size 1.27 1.27)
					(thickness 0.15)
				)
				(justify left bottom)
				(hide yes)
			)
		)
		(property "Footprint" "antmicro-footprints:R_0402_1005Metric"
			(at 129.54 54.61 0)
			(effects
				(font
					(size 1.27 1.27)
					(thickness 0.15)
				)
				(justify left bottom)
				(hide yes)
			)
		)
		(property "Datasheet" "https://www.bourns.com/docs/product-datasheets/cr.pdf"
			(at 129.54 57.15 0)
			(effects
				(font
					(size 1.27 1.27)
					(thickness 0.15)
				)
				(justify left bottom)
				(hide yes)
			)
		)
		(property "Description" ""
			(at 109.22 39.37 0)
			(effects
				(font
					(size 1.27 1.27)
				)
				(hide yes)
			)
		)
		(property "Manufacturer" "Bourns"
			(at 129.54 62.23 0)
			(effects
				(font
					(size 1.27 1.27)
					(thickness 0.15)
				)
				(justify left bottom)
				(hide yes)
			)
		)
		(property "MPN" "CR0402-FX-2003GLF"
			(at 129.54 59.69 0)
			(effects
				(font
					(size 1.27 1.27)
					(thickness 0.15)
				)
				(justify left bottom)
				(hide yes)
			)
		)
		(property "Val" "200k"
			(at 104.775 38.735 0)
			(effects
				(font
					(size 1.27 1.27)
					(thickness 0.15)
				)
				(justify left bottom)
			)
		)
		(property "License" "Apache-2.0"
			(at 129.54 64.77 0)
			(effects
				(font
					(size 1.27 1.27)
					(thickness 0.15)
				)
				(justify left bottom)
				(hide yes)
			)
		)
		(property "Author" "Antmicro"
			(at 129.54 67.31 0)
			(effects
				(font
					(size 1.27 1.27)
					(thickness 0.15)
				)
				(justify left bottom)
				(hide yes)
			)
		)
		(property "Tolerance" "1%"
			(at 129.54 49.53 0)
			(effects
				(font
					(size 1.27 1.27)
				)
				(justify left bottom)
				(hide yes)
			)
		)
		(pin "1"
		)
		(pin "2"
		)
		(instances
			(project "jetson-orin-baseboard"
				(path ""
					(reference "R258")
					(unit 1)
				)
			)
		)
	)
	(symbol
		(lib_id "antmicroResistors0402:R_0R_0402")
		(at 327.66 73.66 0)
		(unit 1)
		(exclude_from_sim no)
		(in_bom yes)
		(on_board yes)
		(dnp no)
		(property "Reference" "R268"
			(at 332.74 73.025 0)
			(effects
				(font
					(size 1.27 1.27)
				)
				(justify left bottom)
			)
		)
		(property "Value" "R_0R_0402"
			(at 347.98 86.36 0)
			(effects
				(font
					(size 1.27 1.27)
					(thickness 0.15)
				)
				(justify left bottom)
				(hide yes)
			)
		)
		(property "Footprint" "antmicro-footprints:R_0402_1005Metric"
			(at 347.98 88.9 0)
			(effects
				(font
					(size 1.27 1.27)
					(thickness 0.15)
				)
				(justify left bottom)
				(hide yes)
			)
		)
		(property "Datasheet" "https://industrial.panasonic.com/cdbs/www-data/pdf/RDA0000/AOA0000C301.pdf"
			(at 347.98 91.44 0)
			(effects
				(font
					(size 1.27 1.27)
					(thickness 0.15)
				)
				(justify left bottom)
				(hide yes)
			)
		)
		(property "Description" ""
			(at 327.66 73.66 0)
			(effects
				(font
					(size 1.27 1.27)
				)
				(hide yes)
			)
		)
		(property "Manufacturer" "Panasonic"
			(at 347.98 96.52 0)
			(effects
				(font
					(size 1.27 1.27)
					(thickness 0.15)
				)
				(justify left bottom)
				(hide yes)
			)
		)
		(property "MPN" "ERJ2GE0R00X"
			(at 347.98 93.98 0)
			(effects
				(font
					(size 1.27 1.27)
					(thickness 0.15)
				)
				(justify left bottom)
				(hide yes)
			)
		)
		(property "Val" "0R"
			(at 325.12 73.025 0)
			(effects
				(font
					(size 1.27 1.27)
					(thickness 0.15)
				)
				(justify left bottom)
			)
		)
		(property "License" "Apache-2.0"
			(at 347.98 99.06 0)
			(effects
				(font
					(size 1.27 1.27)
					(thickness 0.15)
				)
				(justify left bottom)
				(hide yes)
			)
		)
		(property "Author" "Antmicro"
			(at 347.98 101.6 0)
			(effects
				(font
					(size 1.27 1.27)
					(thickness 0.15)
				)
				(justify left bottom)
				(hide yes)
			)
		)
		(property "Tolerance" "~"
			(at 347.98 83.82 0)
			(effects
				(font
					(size 1.27 1.27)
				)
				(justify left bottom)
				(hide yes)
			)
		)
		(property "Current" "1A"
			(at 347.98 104.14 0)
			(effects
				(font
					(size 1.27 1.27)
					(thickness 0.15)
				)
				(justify left bottom)
				(hide yes)
			)
		)
		(pin "1"
		)
		(pin "2"
		)
		(instances
			(project "jetson-orin-baseboard"
				(path ""
					(reference "R268")
					(unit 1)
				)
			)
		)
	)
	(symbol
		(lib_id "antmicropower:GND")
		(at 328.93 213.36 0)
		(unit 1)
		(exclude_from_sim no)
		(in_bom yes)
		(on_board yes)
		(dnp no)
		(property "Reference" "#PWR0345"
			(at 328.93 219.71 0)
			(effects
				(font
					(size 1.27 1.27)
				)
				(justify left bottom)
				(hide yes)
			)
		)
		(property "Value" "GND"
			(at 328.93 217.17 0)
			(effects
				(font
					(size 1.27 1.27)
					(thickness 0.15)
				)
			)
		)
		(property "Footprint" ""
			(at 337.82 220.98 0)
			(effects
				(font
					(size 1.27 1.27)
					(thickness 0.15)
				)
				(justify left bottom)
				(hide yes)
			)
		)
		(property "Datasheet" ""
			(at 337.82 226.06 0)
			(effects
				(font
					(size 1.27 1.27)
					(thickness 0.15)
				)
				(justify left bottom)
				(hide yes)
			)
		)
		(property "Description" ""
			(at 328.93 213.36 0)
			(effects
				(font
					(size 1.27 1.27)
				)
				(hide yes)
			)
		)
		(property "Author" "Antmicro"
			(at 337.82 220.98 0)
			(effects
				(font
					(size 1.27 1.27)
					(thickness 0.15)
				)
				(justify left bottom)
				(hide yes)
			)
		)
		(property "License" "Apache-2.0"
			(at 337.82 223.52 0)
			(effects
				(font
					(size 1.27 1.27)
					(thickness 0.15)
				)
				(justify left bottom)
				(hide yes)
			)
		)
		(pin "1"
		)
		(instances
			(project "jetson-orin-baseboard"
				(path ""
					(reference "#PWR0345")
					(unit 1)
				)
			)
		)
	)
	(symbol
		(lib_id "antmicroResistors0402:R_499k_0402")
		(at 214.63 212.09 90)
		(unit 1)
		(exclude_from_sim no)
		(in_bom yes)
		(on_board yes)
		(dnp no)
		(property "Reference" "R176"
			(at 215.9 208.28 90)
			(effects
				(font
					(size 1.27 1.27)
					(thickness 0.15)
				)
				(justify right)
			)
		)
		(property "Value" "R_499k_0402"
			(at 227.33 191.77 0)
			(effects
				(font
					(size 1.27 1.27)
					(thickness 0.15)
				)
				(justify left bottom)
				(hide yes)
			)
		)
		(property "Footprint" "antmicro-footprints:R_0402_1005Metric"
			(at 229.87 191.77 0)
			(effects
				(font
					(size 1.27 1.27)
					(thickness 0.15)
				)
				(justify left bottom)
				(hide yes)
			)
		)
		(property "Datasheet" "https://www.mouser.com/datasheet/2/54/cr-1858361.pdf"
			(at 232.41 191.77 0)
			(effects
				(font
					(size 1.27 1.27)
					(thickness 0.15)
				)
				(justify left bottom)
				(hide yes)
			)
		)
		(property "Description" ""
			(at 214.63 212.09 0)
			(effects
				(font
					(size 1.27 1.27)
				)
				(hide yes)
			)
		)
		(property "MPN" "CR0402-FX-4993GLF"
			(at 234.95 191.77 0)
			(effects
				(font
					(size 1.27 1.27)
					(thickness 0.15)
				)
				(justify left bottom)
				(hide yes)
			)
		)
		(property "Manufacturer" "Bourns"
			(at 237.49 191.77 0)
			(effects
				(font
					(size 1.27 1.27)
					(thickness 0.15)
				)
				(justify left bottom)
				(hide yes)
			)
		)
		(property "License" "Apache-2.0"
			(at 240.03 191.77 0)
			(effects
				(font
					(size 1.27 1.27)
					(thickness 0.15)
				)
				(justify left bottom)
				(hide yes)
			)
		)
		(property "Author" "Antmicro"
			(at 242.57 191.77 0)
			(effects
				(font
					(size 1.27 1.27)
					(thickness 0.15)
				)
				(justify left bottom)
				(hide yes)
			)
		)
		(property "Val" "499k"
			(at 215.9 210.82 90)
			(effects
				(font
					(size 1.27 1.27)
					(thickness 0.15)
				)
				(justify right)
			)
		)
		(property "Tolerance" "1%"
			(at 224.79 191.77 0)
			(effects
				(font
					(size 1.27 1.27)
				)
				(justify left bottom)
				(hide yes)
			)
		)
		(pin "2"
		)
		(pin "1"
		)
		(instances
			(project "jetson-orin-baseboard"
				(path ""
					(reference "R176")
					(unit 1)
				)
			)
		)
	)
	(symbol
		(lib_id "antmicroFixedInductors:L_1u_20A_Bourns-SRP6050CA")
		(at 293.37 134.62 0)
		(unit 1)
		(exclude_from_sim no)
		(in_bom yes)
		(on_board yes)
		(dnp no)
		(fields_autoplaced yes)
		(property "Reference" "L4"
			(at 295.91 129.54 0)
			(effects
				(font
					(size 1.27 1.27)
					(thickness 0.15)
				)
			)
		)
		(property "Value" "L_1u_20A_Bourns-SRP6050CA"
			(at 307.34 137.16 0)
			(effects
				(font
					(size 1.27 1.27)
					(thickness 0.15)
				)
				(justify left bottom)
				(hide yes)
			)
		)
		(property "Footprint" "antmicro-footprints:L_Bourns-SRP6050CA"
			(at 307.34 142.24 0)
			(effects
				(font
					(size 1.27 1.27)
					(thickness 0.15)
				)
				(justify left bottom)
				(hide yes)
			)
		)
		(property "Datasheet" "https://www.bourns.com/docs/Product-Datasheets/SRP6050CA.pdf"
			(at 307.34 144.78 0)
			(effects
				(font
					(size 1.27 1.27)
					(thickness 0.15)
				)
				(justify left bottom)
				(hide yes)
			)
		)
		(property "Description" ""
			(at 293.37 134.62 0)
			(effects
				(font
					(size 1.27 1.27)
				)
				(hide yes)
			)
		)
		(property "Val" "1u/20A"
			(at 295.91 132.08 0)
			(effects
				(font
					(size 1.27 1.27)
					(thickness 0.15)
				)
			)
		)
		(property "Manufacturer" "Bourns"
			(at 307.34 147.32 0)
			(effects
				(font
					(size 1.27 1.27)
					(thickness 0.15)
				)
				(justify left bottom)
				(hide yes)
			)
		)
		(property "MPN" "SRP6050CA-1R0M"
			(at 307.34 149.86 0)
			(effects
				(font
					(size 1.27 1.27)
					(thickness 0.15)
				)
				(justify left bottom)
				(hide yes)
			)
		)
		(property "ISat" "23 A"
			(at 307.34 151.13 0)
			(effects
				(font
					(size 1.27 1.27)
				)
				(justify left)
				(hide yes)
			)
		)
		(property "IMax" "20 A"
			(at 307.34 154.94 0)
			(effects
				(font
					(size 1.27 1.27)
					(thickness 0.15)
				)
				(justify left bottom)
				(hide yes)
			)
		)
		(property "Size" "6.6x6.4"
			(at 307.34 157.48 0)
			(effects
				(font
					(size 1.27 1.27)
					(thickness 0.15)
				)
				(justify left bottom)
				(hide yes)
			)
		)
		(property "Author" "Antmicro"
			(at 307.34 160.02 0)
			(effects
				(font
					(size 1.27 1.27)
					(thickness 0.15)
				)
				(justify left bottom)
				(hide yes)
			)
		)
		(property "License" "Apache-2.0"
			(at 307.34 162.56 0)
			(effects
				(font
					(size 1.27 1.27)
					(thickness 0.15)
				)
				(justify left bottom)
				(hide yes)
			)
		)
		(pin "2"
		)
		(pin "1"
		)
		(instances
			(project "jetson-orin-baseboard"
				(path ""
					(reference "L4")
					(unit 1)
				)
			)
		)
	)
	(symbol
		(lib_id "antmicroDiodesRectifiersSingle:RB521S30T1G")
		(at 95.25 73.66 180)
		(unit 1)
		(exclude_from_sim no)
		(in_bom yes)
		(on_board yes)
		(dnp no)
		(property "Reference" "D36"
			(at 92.71 68.58 0)
			(effects
				(font
					(size 1.27 1.27)
				)
			)
		)
		(property "Value" "RB521S30T1G"
			(at 72.39 58.42 0)
			(effects
				(font
					(size 1.27 1.27)
					(thickness 0.15)
				)
				(justify left bottom)
				(hide yes)
			)
		)
		(property "Footprint" "antmicro-footprints:SOD-523"
			(at 72.39 63.5 0)
			(effects
				(font
					(size 1.27 1.27)
					(thickness 0.15)
				)
				(justify left bottom)
				(hide yes)
			)
		)
		(property "Datasheet" "https://www.onsemi.com/pdf/datasheet/rb521s30t1-d.pdf"
			(at 72.39 60.96 0)
			(effects
				(font
					(size 1.27 1.27)
					(thickness 0.15)
				)
				(justify left bottom)
				(hide yes)
			)
		)
		(property "Description" ""
			(at 95.25 73.66 0)
			(effects
				(font
					(size 1.27 1.27)
				)
				(hide yes)
			)
		)
		(property "MPN" "RB521S30T1G"
			(at 92.71 71.12 0)
			(effects
				(font
					(size 1.27 1.27)
					(thickness 0.15)
				)
			)
		)
		(property "Manufacturer" "ON Semiconductor"
			(at 72.39 55.88 0)
			(effects
				(font
					(size 1.27 1.27)
					(thickness 0.15)
				)
				(justify left bottom)
				(hide yes)
			)
		)
		(property "Author" "Antmicro"
			(at 72.39 53.34 0)
			(effects
				(font
					(size 1.27 1.27)
					(thickness 0.15)
				)
				(justify left bottom)
				(hide yes)
			)
		)
		(property "License" "Apache-2.0"
			(at 72.39 50.8 0)
			(effects
				(font
					(size 1.27 1.27)
					(thickness 0.15)
				)
				(justify left bottom)
				(hide yes)
			)
		)
		(pin "1"
		)
		(pin "2"
		)
		(instances
			(project "jetson-orin-baseboard"
				(path ""
					(reference "D36")
					(unit 1)
				)
			)
		)
	)
	(symbol
		(lib_id "antmicroCapacitors0402:C_100n_0402")
		(at 288.29 129.54 180)
		(unit 1)
		(exclude_from_sim no)
		(in_bom yes)
		(on_board yes)
		(dnp no)
		(fields_autoplaced yes)
		(property "Reference" "C102"
			(at 285.7436 123.19 0)
			(effects
				(font
					(size 1.27 1.27)
				)
			)
		)
		(property "Value" "C_100n_0402"
			(at 267.97 119.38 0)
			(effects
				(font
					(size 1.27 1.27)
					(thickness 0.15)
				)
				(justify left bottom)
				(hide yes)
			)
		)
		(property "Footprint" "antmicro-footprints:C_0402_1005Metric"
			(at 267.97 116.84 0)
			(effects
				(font
					(size 1.27 1.27)
					(thickness 0.15)
				)
				(justify left bottom)
				(hide yes)
			)
		)
		(property "Datasheet" "https://www.murata.com/products/productdetail?partno=GRM155R61H104KE14%23"
			(at 267.97 114.3 0)
			(effects
				(font
					(size 1.27 1.27)
					(thickness 0.15)
				)
				(justify left bottom)
				(hide yes)
			)
		)
		(property "Description" ""
			(at 288.29 129.54 0)
			(effects
				(font
					(size 1.27 1.27)
				)
				(hide yes)
			)
		)
		(property "Manufacturer" "Murata"
			(at 267.97 109.22 0)
			(effects
				(font
					(size 1.27 1.27)
					(thickness 0.15)
				)
				(justify left bottom)
				(hide yes)
			)
		)
		(property "MPN" "GRM155R61H104KE14D"
			(at 267.97 111.76 0)
			(effects
				(font
					(size 1.27 1.27)
					(thickness 0.15)
				)
				(justify left bottom)
				(hide yes)
			)
		)
		(property "Val" "100n"
			(at 285.7436 125.73 0)
			(effects
				(font
					(size 1.27 1.27)
					(thickness 0.15)
				)
			)
		)
		(property "License" "Apache-2.0"
			(at 267.97 106.68 0)
			(effects
				(font
					(size 1.27 1.27)
					(thickness 0.15)
				)
				(justify left bottom)
				(hide yes)
			)
		)
		(property "Author" "Antmicro"
			(at 267.97 104.14 0)
			(effects
				(font
					(size 1.27 1.27)
					(thickness 0.15)
				)
				(justify left bottom)
				(hide yes)
			)
		)
		(property "Voltage" "50V"
			(at 267.97 101.6 0)
			(effects
				(font
					(size 1.27 1.27)
				)
				(justify left bottom)
				(hide yes)
			)
		)
		(property "Dielectric" "X5R"
			(at 267.97 99.06 0)
			(effects
				(font
					(size 1.27 1.27)
				)
				(justify left bottom)
				(hide yes)
			)
		)
		(pin "1"
		)
		(pin "2"
		)
		(instances
			(project "jetson-orin-baseboard"
				(path ""
					(reference "C102")
					(unit 1)
				)
			)
		)
	)
	(symbol
		(lib_id "antmicropower:GND")
		(at 50.8 153.67 0)
		(unit 1)
		(exclude_from_sim no)
		(in_bom yes)
		(on_board yes)
		(dnp no)
		(property "Reference" "#PWR045"
			(at 50.8 160.02 0)
			(effects
				(font
					(size 1.27 1.27)
				)
				(justify left bottom)
				(hide yes)
			)
		)
		(property "Value" "GND"
			(at 50.8 157.48 0)
			(effects
				(font
					(size 1.27 1.27)
					(thickness 0.15)
				)
			)
		)
		(property "Footprint" ""
			(at 59.69 161.29 0)
			(effects
				(font
					(size 1.27 1.27)
					(thickness 0.15)
				)
				(justify left bottom)
				(hide yes)
			)
		)
		(property "Datasheet" ""
			(at 59.69 166.37 0)
			(effects
				(font
					(size 1.27 1.27)
					(thickness 0.15)
				)
				(justify left bottom)
				(hide yes)
			)
		)
		(property "Description" ""
			(at 50.8 153.67 0)
			(effects
				(font
					(size 1.27 1.27)
				)
				(hide yes)
			)
		)
		(property "Author" "Antmicro"
			(at 59.69 161.29 0)
			(effects
				(font
					(size 1.27 1.27)
					(thickness 0.15)
				)
				(justify left bottom)
				(hide yes)
			)
		)
		(property "License" "Apache-2.0"
			(at 59.69 163.83 0)
			(effects
				(font
					(size 1.27 1.27)
					(thickness 0.15)
				)
				(justify left bottom)
				(hide yes)
			)
		)
		(pin "1"
		)
		(instances
			(project "jetson-orin-baseboard"
				(path ""
					(reference "#PWR045")
					(unit 1)
				)
			)
		)
	)
	(symbol
		(lib_id "antmicropower:VCC")
		(at 318.77 27.94 0)
		(unit 1)
		(exclude_from_sim no)
		(in_bom yes)
		(on_board yes)
		(dnp no)
		(property "Reference" "#PWR0282"
			(at 318.77 31.75 0)
			(effects
				(font
					(size 1.27 1.27)
				)
				(justify left bottom)
				(hide yes)
			)
		)
		(property "Value" "VCC"
			(at 316.865 24.13 0)
			(effects
				(font
					(size 1.27 1.27)
				)
				(justify left)
			)
		)
		(property "Footprint" ""
			(at 318.77 27.94 0)
			(effects
				(font
					(size 1.27 1.27)
				)
				(hide yes)
			)
		)
		(property "Datasheet" ""
			(at 318.77 27.94 0)
			(effects
				(font
					(size 1.27 1.27)
				)
				(hide yes)
			)
		)
		(property "Description" ""
			(at 318.77 27.94 0)
			(effects
				(font
					(size 1.27 1.27)
				)
				(hide yes)
			)
		)
		(pin "1"
		)
		(instances
			(project "jetson-orin-baseboard"
				(path ""
					(reference "#PWR0282")
					(unit 1)
				)
			)
		)
	)
	(symbol
		(lib_id "antmicroPMICVoltageRegulatorsLinear:TPS7A0518P_SOT23-5")
		(at 339.09 71.12 0)
		(unit 1)
		(exclude_from_sim no)
		(in_bom yes)
		(on_board yes)
		(dnp no)
		(property "Reference" "U42"
			(at 346.71 64.77 0)
			(effects
				(font
					(size 1.27 1.27)
				)
			)
		)
		(property "Value" "TPS7A0518P_SOT23-5"
			(at 365.76 74.93 0)
			(effects
				(font
					(size 1.27 1.27)
					(thickness 0.15)
				)
				(justify left bottom)
				(hide yes)
			)
		)
		(property "Footprint" "antmicro-footprints:SOT-23-5"
			(at 365.76 77.47 0)
			(effects
				(font
					(size 1.27 1.27)
					(thickness 0.15)
				)
				(justify left bottom)
				(hide yes)
			)
		)
		(property "Datasheet" "https://www.ti.com/lit/ds/symlink/tps7a05.pdf?ts=1678973651768&ref_url=https%253A%252F%252Fwww.google.com%252F"
			(at 365.76 80.01 0)
			(effects
				(font
					(size 1.27 1.27)
					(thickness 0.15)
				)
				(justify left bottom)
				(hide yes)
			)
		)
		(property "Description" ""
			(at 339.09 71.12 0)
			(effects
				(font
					(size 1.27 1.27)
				)
				(hide yes)
			)
		)
		(property "MPN" "TPS7A0518PDBVT"
			(at 346.71 67.31 0)
			(effects
				(font
					(size 1.27 1.27)
					(thickness 0.15)
				)
			)
		)
		(property "Manufacturer" "Texas Instruments"
			(at 365.76 85.09 0)
			(effects
				(font
					(size 1.27 1.27)
					(thickness 0.15)
				)
				(justify left bottom)
				(hide yes)
			)
		)
		(property "Author" "Antmicro"
			(at 365.76 87.63 0)
			(effects
				(font
					(size 1.27 1.27)
					(thickness 0.15)
				)
				(justify left bottom)
				(hide yes)
			)
		)
		(property "License" "Apache-2.0"
			(at 365.76 90.17 0)
			(effects
				(font
					(size 1.27 1.27)
					(thickness 0.15)
				)
				(justify left bottom)
				(hide yes)
			)
		)
		(pin "1"
		)
		(pin "2"
		)
		(pin "3"
		)
		(pin "4"
		)
		(pin "5"
		)
		(instances
			(project "jetson-orin-baseboard"
				(path ""
					(reference "U42")
					(unit 1)
				)
			)
		)
	)
	(symbol
		(lib_id "antmicropower:+5V")
		(at 256.54 261.62 0)
		(unit 1)
		(exclude_from_sim no)
		(in_bom yes)
		(on_board yes)
		(dnp no)
		(property "Reference" "#PWR04"
			(at 256.54 265.43 0)
			(effects
				(font
					(size 1.27 1.27)
				)
				(justify left bottom)
				(hide yes)
			)
		)
		(property "Value" "+5V_SoM"
			(at 256.54 257.81 0)
			(effects
				(font
					(size 1.27 1.27)
					(thickness 0.15)
				)
			)
		)
		(property "Footprint" ""
			(at 271.78 269.24 0)
			(effects
				(font
					(size 1.27 1.27)
					(thickness 0.15)
				)
				(justify left bottom)
				(hide yes)
			)
		)
		(property "Datasheet" ""
			(at 271.78 271.78 0)
			(effects
				(font
					(size 1.27 1.27)
					(thickness 0.15)
				)
				(justify left bottom)
				(hide yes)
			)
		)
		(property "Description" ""
			(at 256.54 261.62 0)
			(effects
				(font
					(size 1.27 1.27)
				)
				(hide yes)
			)
		)
		(property "Author" "Antmicro"
			(at 271.78 269.24 0)
			(effects
				(font
					(size 1.27 1.27)
					(thickness 0.15)
				)
				(justify left bottom)
				(hide yes)
			)
		)
		(property "License" "Apache-2.0"
			(at 271.78 271.78 0)
			(effects
				(font
					(size 1.27 1.27)
					(thickness 0.15)
				)
				(justify left bottom)
				(hide yes)
			)
		)
		(pin "1"
		)
		(instances
			(project "jetson-orin-baseboard"
				(path ""
					(reference "#PWR04")
					(unit 1)
				)
			)
		)
	)
	(symbol
		(lib_id "antmicropower:GND")
		(at 262.89 279.4 0)
		(unit 1)
		(exclude_from_sim no)
		(in_bom yes)
		(on_board yes)
		(dnp no)
		(property "Reference" "#PWR0370"
			(at 262.89 285.75 0)
			(effects
				(font
					(size 1.27 1.27)
				)
				(justify left bottom)
				(hide yes)
			)
		)
		(property "Value" "GND"
			(at 262.89 283.21 0)
			(effects
				(font
					(size 1.27 1.27)
					(thickness 0.15)
				)
			)
		)
		(property "Footprint" ""
			(at 271.78 287.02 0)
			(effects
				(font
					(size 1.27 1.27)
					(thickness 0.15)
				)
				(justify left bottom)
				(hide yes)
			)
		)
		(property "Datasheet" ""
			(at 271.78 292.1 0)
			(effects
				(font
					(size 1.27 1.27)
					(thickness 0.15)
				)
				(justify left bottom)
				(hide yes)
			)
		)
		(property "Description" ""
			(at 262.89 279.4 0)
			(effects
				(font
					(size 1.27 1.27)
				)
				(hide yes)
			)
		)
		(property "Author" "Antmicro"
			(at 271.78 287.02 0)
			(effects
				(font
					(size 1.27 1.27)
					(thickness 0.15)
				)
				(justify left bottom)
				(hide yes)
			)
		)
		(property "License" "Apache-2.0"
			(at 271.78 289.56 0)
			(effects
				(font
					(size 1.27 1.27)
					(thickness 0.15)
				)
				(justify left bottom)
				(hide yes)
			)
		)
		(pin "1"
		)
		(instances
			(project "jetson-orin-baseboard"
				(path ""
					(reference "#PWR0370")
					(unit 1)
				)
			)
		)
	)
	(symbol
		(lib_id "antmicropower:+5V")
		(at 299.72 69.85 0)
		(unit 1)
		(exclude_from_sim no)
		(in_bom yes)
		(on_board yes)
		(dnp no)
		(property "Reference" "#PWR0280"
			(at 299.72 73.66 0)
			(effects
				(font
					(size 1.27 1.27)
				)
				(justify left bottom)
				(hide yes)
			)
		)
		(property "Value" "+5V"
			(at 297.18 66.04 0)
			(effects
				(font
					(size 1.27 1.27)
					(thickness 0.15)
				)
				(justify left)
			)
		)
		(property "Footprint" ""
			(at 314.96 77.47 0)
			(effects
				(font
					(size 1.27 1.27)
					(thickness 0.15)
				)
				(justify left bottom)
				(hide yes)
			)
		)
		(property "Datasheet" ""
			(at 314.96 80.01 0)
			(effects
				(font
					(size 1.27 1.27)
					(thickness 0.15)
				)
				(justify left bottom)
				(hide yes)
			)
		)
		(property "Description" ""
			(at 299.72 69.85 0)
			(effects
				(font
					(size 1.27 1.27)
				)
				(hide yes)
			)
		)
		(property "Author" "Antmicro"
			(at 314.96 77.47 0)
			(effects
				(font
					(size 1.27 1.27)
					(thickness 0.15)
				)
				(justify left bottom)
				(hide yes)
			)
		)
		(property "License" "Apache-2.0"
			(at 314.96 80.01 0)
			(effects
				(font
					(size 1.27 1.27)
					(thickness 0.15)
				)
				(justify left bottom)
				(hide yes)
			)
		)
		(pin "1"
		)
		(instances
			(project "jetson-orin-baseboard"
				(path ""
					(reference "#PWR0280")
					(unit 1)
				)
			)
		)
	)
	(symbol
		(lib_id "antmicropower:GND")
		(at 299.72 78.74 0)
		(unit 1)
		(exclude_from_sim no)
		(in_bom yes)
		(on_board yes)
		(dnp no)
		(property "Reference" "#PWR0272"
			(at 299.72 85.09 0)
			(effects
				(font
					(size 1.27 1.27)
				)
				(justify left bottom)
				(hide yes)
			)
		)
		(property "Value" "GND"
			(at 299.72 82.55 0)
			(effects
				(font
					(size 1.27 1.27)
					(thickness 0.15)
				)
			)
		)
		(property "Footprint" ""
			(at 308.61 86.36 0)
			(effects
				(font
					(size 1.27 1.27)
					(thickness 0.15)
				)
				(justify left bottom)
				(hide yes)
			)
		)
		(property "Datasheet" ""
			(at 308.61 91.44 0)
			(effects
				(font
					(size 1.27 1.27)
					(thickness 0.15)
				)
				(justify left bottom)
				(hide yes)
			)
		)
		(property "Description" ""
			(at 299.72 78.74 0)
			(effects
				(font
					(size 1.27 1.27)
				)
				(hide yes)
			)
		)
		(property "Author" "Antmicro"
			(at 308.61 86.36 0)
			(effects
				(font
					(size 1.27 1.27)
					(thickness 0.15)
				)
				(justify left bottom)
				(hide yes)
			)
		)
		(property "License" "Apache-2.0"
			(at 308.61 88.9 0)
			(effects
				(font
					(size 1.27 1.27)
					(thickness 0.15)
				)
				(justify left bottom)
				(hide yes)
			)
		)
		(pin "1"
		)
		(instances
			(project "jetson-orin-baseboard"
				(path ""
					(reference "#PWR0272")
					(unit 1)
				)
			)
		)
	)
	(symbol
		(lib_id "antmicroResistors0402:R_4k7_0402")
		(at 132.08 180.34 90)
		(unit 1)
		(exclude_from_sim no)
		(in_bom yes)
		(on_board yes)
		(dnp no)
		(property "Reference" "R165"
			(at 133.35 176.53 90)
			(effects
				(font
					(size 1.27 1.27)
				)
				(justify right)
			)
		)
		(property "Value" "R_4k7_0402"
			(at 144.78 160.02 0)
			(effects
				(font
					(size 1.27 1.27)
					(thickness 0.15)
				)
				(justify left bottom)
				(hide yes)
			)
		)
		(property "Footprint" "antmicro-footprints:R_0402_1005Metric"
			(at 147.32 160.02 0)
			(effects
				(font
					(size 1.27 1.27)
					(thickness 0.15)
				)
				(justify left bottom)
				(hide yes)
			)
		)
		(property "Datasheet" "https://www.bourns.com/docs/product-datasheets/cr.pdf"
			(at 149.86 160.02 0)
			(effects
				(font
					(size 1.27 1.27)
					(thickness 0.15)
				)
				(justify left bottom)
				(hide yes)
			)
		)
		(property "Description" ""
			(at 132.08 180.34 0)
			(effects
				(font
					(size 1.27 1.27)
				)
				(hide yes)
			)
		)
		(property "Manufacturer" "Bourns"
			(at 154.94 160.02 0)
			(effects
				(font
					(size 1.27 1.27)
					(thickness 0.15)
				)
				(justify left bottom)
				(hide yes)
			)
		)
		(property "MPN" "CR0402-FX-4701GLF"
			(at 152.4 160.02 0)
			(effects
				(font
					(size 1.27 1.27)
					(thickness 0.15)
				)
				(justify left bottom)
				(hide yes)
			)
		)
		(property "Val" "4k7"
			(at 133.35 179.07 90)
			(effects
				(font
					(size 1.27 1.27)
					(thickness 0.15)
				)
				(justify right)
			)
		)
		(property "License" "Apache-2.0"
			(at 157.48 160.02 0)
			(effects
				(font
					(size 1.27 1.27)
					(thickness 0.15)
				)
				(justify left bottom)
				(hide yes)
			)
		)
		(property "Author" "Antmicro"
			(at 160.02 160.02 0)
			(effects
				(font
					(size 1.27 1.27)
					(thickness 0.15)
				)
				(justify left bottom)
				(hide yes)
			)
		)
		(property "Tolerance" "1%"
			(at 142.24 160.02 0)
			(effects
				(font
					(size 1.27 1.27)
				)
				(justify left bottom)
				(hide yes)
			)
		)
		(pin "1"
		)
		(pin "2"
		)
		(instances
			(project "jetson-orin-baseboard"
				(path ""
					(reference "R165")
					(unit 1)
				)
			)
		)
	)
	(symbol
		(lib_id "antmicroCapacitorsmisc:C_22u_25V_0805")
		(at 198.12 147.32 90)
		(unit 1)
		(exclude_from_sim no)
		(in_bom yes)
		(on_board yes)
		(dnp no)
		(property "Reference" "C152"
			(at 198.755 142.875 90)
			(effects
				(font
					(size 1.27 1.27)
					(thickness 0.15)
				)
				(justify right)
			)
		)
		(property "Value" "C_22u_25V_0805"
			(at 208.28 127 0)
			(effects
				(font
					(size 1.27 1.27)
					(thickness 0.15)
				)
				(justify left bottom)
				(hide yes)
			)
		)
		(property "Footprint" "antmicro-footprints:C_0805_2012Metric"
			(at 210.82 127 0)
			(effects
				(font
					(size 1.27 1.27)
					(thickness 0.15)
				)
				(justify left bottom)
				(hide yes)
			)
		)
		(property "Datasheet" "https://product.samsungsem.com/mlcc/CL21A226MAYNNN.do"
			(at 213.36 127 0)
			(effects
				(font
					(size 1.27 1.27)
					(thickness 0.15)
				)
				(justify left bottom)
				(hide yes)
			)
		)
		(property "Description" ""
			(at 198.12 147.32 0)
			(effects
				(font
					(size 1.27 1.27)
				)
				(hide yes)
			)
		)
		(property "MPN" "CL21A226MAYNNNE"
			(at 215.9 127 0)
			(effects
				(font
					(size 1.27 1.27)
					(thickness 0.15)
				)
				(justify left bottom)
				(hide yes)
			)
		)
		(property "Manufacturer" "Samsung Electro-Mechanics"
			(at 218.44 127 0)
			(effects
				(font
					(size 1.27 1.27)
					(thickness 0.15)
				)
				(justify left bottom)
				(hide yes)
			)
		)
		(property "License" "Apache-2.0"
			(at 220.98 127 0)
			(effects
				(font
					(size 1.27 1.27)
					(thickness 0.15)
				)
				(justify left bottom)
				(hide yes)
			)
		)
		(property "Author" "Antmicro"
			(at 223.52 127 0)
			(effects
				(font
					(size 1.27 1.27)
					(thickness 0.15)
				)
				(justify left bottom)
				(hide yes)
			)
		)
		(property "Val" "22u"
			(at 198.755 146.685 90)
			(effects
				(font
					(size 1.27 1.27)
					(thickness 0.15)
				)
				(justify right)
			)
		)
		(property "Voltage" "25V"
			(at 198.755 149.225 90)
			(effects
				(font
					(size 1.27 1.27)
				)
				(justify right)
			)
		)
		(property "Dielectric" "X5R"
			(at 228.6 127 0)
			(effects
				(font
					(size 1.27 1.27)
				)
				(justify left bottom)
				(hide yes)
			)
		)
		(property "Public" "False"
			(at 231.14 127 0)
			(effects
				(font
					(size 1.27 1.27)
				)
				(justify left bottom)
				(hide yes)
			)
		)
		(pin "1"
		)
		(pin "2"
		)
		(instances
			(project "jetson-orin-baseboard"
				(path ""
					(reference "C152")
					(unit 1)
				)
			)
		)
	)
	(symbol
		(lib_id "antmicroCapacitors0402:C_100n_0402")
		(at 236.22 55.88 90)
		(unit 1)
		(exclude_from_sim no)
		(in_bom yes)
		(on_board yes)
		(dnp no)
		(property "Reference" "C124"
			(at 238.125 52.07 90)
			(effects
				(font
					(size 1.27 1.27)
				)
				(justify right)
			)
		)
		(property "Value" "C_100n_0402"
			(at 246.38 35.56 0)
			(effects
				(font
					(size 1.27 1.27)
					(thickness 0.15)
				)
				(justify left bottom)
				(hide yes)
			)
		)
		(property "Footprint" "antmicro-footprints:C_0402_1005Metric"
			(at 248.92 35.56 0)
			(effects
				(font
					(size 1.27 1.27)
					(thickness 0.15)
				)
				(justify left bottom)
				(hide yes)
			)
		)
		(property "Datasheet" "https://www.murata.com/products/productdetail?partno=GRM155R61H104KE14%23"
			(at 251.46 35.56 0)
			(effects
				(font
					(size 1.27 1.27)
					(thickness 0.15)
				)
				(justify left bottom)
				(hide yes)
			)
		)
		(property "Description" ""
			(at 236.22 55.88 0)
			(effects
				(font
					(size 1.27 1.27)
				)
				(hide yes)
			)
		)
		(property "Manufacturer" "Murata"
			(at 256.54 35.56 0)
			(effects
				(font
					(size 1.27 1.27)
					(thickness 0.15)
				)
				(justify left bottom)
				(hide yes)
			)
		)
		(property "MPN" "GRM155R61H104KE14D"
			(at 254 35.56 0)
			(effects
				(font
					(size 1.27 1.27)
					(thickness 0.15)
				)
				(justify left bottom)
				(hide yes)
			)
		)
		(property "Val" "100n"
			(at 238.125 54.61 90)
			(effects
				(font
					(size 1.27 1.27)
					(thickness 0.15)
				)
				(justify right)
			)
		)
		(property "License" "Apache-2.0"
			(at 259.08 35.56 0)
			(effects
				(font
					(size 1.27 1.27)
					(thickness 0.15)
				)
				(justify left bottom)
				(hide yes)
			)
		)
		(property "Author" "Antmicro"
			(at 261.62 35.56 0)
			(effects
				(font
					(size 1.27 1.27)
					(thickness 0.15)
				)
				(justify left bottom)
				(hide yes)
			)
		)
		(property "Voltage" "50V"
			(at 264.16 35.56 0)
			(effects
				(font
					(size 1.27 1.27)
				)
				(justify left bottom)
				(hide yes)
			)
		)
		(property "Dielectric" "X5R"
			(at 266.7 35.56 0)
			(effects
				(font
					(size 1.27 1.27)
				)
				(justify left bottom)
				(hide yes)
			)
		)
		(pin "1"
		)
		(pin "2"
		)
		(instances
			(project "jetson-orin-baseboard"
				(path ""
					(reference "C124")
					(unit 1)
				)
			)
		)
	)
	(symbol
		(lib_id "antmicroTransistorsFETsMOSFETsSingle:PJE138K")
		(at 156.21 262.89 0)
		(unit 1)
		(exclude_from_sim no)
		(in_bom yes)
		(on_board yes)
		(dnp no)
		(property "Reference" "Q22"
			(at 165.1 259.08 0)
			(effects
				(font
					(size 1.27 1.27)
					(thickness 0.15)
				)
				(justify left)
			)
		)
		(property "Value" "PJE138K"
			(at 179.07 271.78 0)
			(effects
				(font
					(size 1.27 1.27)
					(thickness 0.15)
				)
				(justify left bottom)
				(hide yes)
			)
		)
		(property "Footprint" "antmicro-footprints:SOT-523"
			(at 179.07 274.32 0)
			(effects
				(font
					(size 1.27 1.27)
					(thickness 0.15)
				)
				(justify left bottom)
				(hide yes)
			)
		)
		(property "Datasheet" "https://www.mouser.com/datasheet/2/1057/PJE138K-1876698.pdf"
			(at 179.07 276.86 0)
			(effects
				(font
					(size 1.27 1.27)
					(thickness 0.15)
				)
				(justify left bottom)
				(hide yes)
			)
		)
		(property "Description" ""
			(at 156.21 262.89 0)
			(effects
				(font
					(size 1.27 1.27)
				)
				(hide yes)
			)
		)
		(property "MPN" "PJE138K_R1_00001"
			(at 165.1 261.62 0)
			(effects
				(font
					(size 1.27 1.27)
					(thickness 0.15)
				)
				(justify left)
			)
		)
		(property "Manufacturer" "PANJIT"
			(at 179.07 281.94 0)
			(effects
				(font
					(size 1.27 1.27)
					(thickness 0.15)
				)
				(justify left bottom)
				(hide yes)
			)
		)
		(property "Author" "Antmicro"
			(at 179.07 284.48 0)
			(effects
				(font
					(size 1.27 1.27)
					(thickness 0.15)
				)
				(justify left bottom)
				(hide yes)
			)
		)
		(property "License" "Apache-2.0"
			(at 179.07 287.02 0)
			(effects
				(font
					(size 1.27 1.27)
					(thickness 0.15)
				)
				(justify left bottom)
				(hide yes)
			)
		)
		(pin "2"
		)
		(pin "3"
		)
		(pin "1"
		)
		(instances
			(project "jetson-orin-baseboard"
				(path ""
					(reference "Q22")
					(unit 1)
				)
			)
		)
	)
	(symbol
		(lib_id "antmicroResistors0603:R_0R_22.4A_0603")
		(at 58.42 217.17 0)
		(unit 1)
		(exclude_from_sim no)
		(in_bom yes)
		(on_board yes)
		(dnp no)
		(property "Reference" "R253"
			(at 63.5 216.535 0)
			(effects
				(font
					(size 1.27 1.27)
				)
				(justify left bottom)
			)
		)
		(property "Value" "R_0R_22.4A_0603"
			(at 60.96 208.28 0)
			(effects
				(font
					(size 1.27 1.27)
					(thickness 0.15)
				)
				(hide yes)
			)
		)
		(property "Footprint" "antmicro-footprints:R_0603_1608Metric"
			(at 73.66 227.33 0)
			(effects
				(font
					(size 1.27 1.27)
					(thickness 0.15)
				)
				(justify left bottom)
				(hide yes)
			)
		)
		(property "Datasheet" "https://fscdn.rohm.com/en/products/databook/datasheet/passive/resistor/chip_resistor/pmr-jpw-e.pdf"
			(at 73.66 229.87 0)
			(effects
				(font
					(size 1.27 1.27)
					(thickness 0.15)
				)
				(justify left bottom)
				(hide yes)
			)
		)
		(property "Description" ""
			(at 58.42 217.17 0)
			(effects
				(font
					(size 1.27 1.27)
				)
				(hide yes)
			)
		)
		(property "Manufacturer" "ROHM Semiconductor"
			(at 73.66 234.95 0)
			(effects
				(font
					(size 1.27 1.27)
					(thickness 0.15)
				)
				(justify left bottom)
				(hide yes)
			)
		)
		(property "MPN" "PMR03EZPJ000"
			(at 73.66 232.41 0)
			(effects
				(font
					(size 1.27 1.27)
					(thickness 0.15)
				)
				(justify left bottom)
				(hide yes)
			)
		)
		(property "Val" "0R"
			(at 55.88 216.535 0)
			(effects
				(font
					(size 1.27 1.27)
					(thickness 0.15)
				)
				(justify left bottom)
			)
		)
		(property "Author" "Antmicro"
			(at 73.66 240.03 0)
			(effects
				(font
					(size 1.27 1.27)
					(thickness 0.15)
				)
				(justify left bottom)
				(hide yes)
			)
		)
		(property "License" "Apache-2.0"
			(at 73.66 242.57 0)
			(effects
				(font
					(size 1.27 1.27)
					(thickness 0.15)
				)
				(justify left bottom)
				(hide yes)
			)
		)
		(property "Max. Curr." "22.4A"
			(at 60.96 219.075 0)
			(effects
				(font
					(size 1.27 1.27)
					(thickness 0.15)
				)
			)
		)
		(property "Tolerance" "template_tolerance"
			(at 78.74 227.33 0)
			(effects
				(font
					(size 1.27 1.27)
				)
				(justify left bottom)
				(hide yes)
			)
		)
		(pin "1"
		)
		(pin "2"
		)
		(instances
			(project "jetson-orin-baseboard"
				(path ""
					(reference "R253")
					(unit 1)
				)
			)
		)
	)
	(symbol
		(lib_id "antmicropower:GND")
		(at 214.63 154.94 0)
		(unit 1)
		(exclude_from_sim no)
		(in_bom yes)
		(on_board yes)
		(dnp no)
		(property "Reference" "#PWR0190"
			(at 214.63 161.29 0)
			(effects
				(font
					(size 1.27 1.27)
				)
				(justify left bottom)
				(hide yes)
			)
		)
		(property "Value" "GND"
			(at 214.63 158.75 0)
			(effects
				(font
					(size 1.27 1.27)
					(thickness 0.15)
				)
			)
		)
		(property "Footprint" ""
			(at 223.52 162.56 0)
			(effects
				(font
					(size 1.27 1.27)
					(thickness 0.15)
				)
				(justify left bottom)
				(hide yes)
			)
		)
		(property "Datasheet" ""
			(at 223.52 167.64 0)
			(effects
				(font
					(size 1.27 1.27)
					(thickness 0.15)
				)
				(justify left bottom)
				(hide yes)
			)
		)
		(property "Description" ""
			(at 214.63 154.94 0)
			(effects
				(font
					(size 1.27 1.27)
				)
				(hide yes)
			)
		)
		(property "Author" "Antmicro"
			(at 223.52 162.56 0)
			(effects
				(font
					(size 1.27 1.27)
					(thickness 0.15)
				)
				(justify left bottom)
				(hide yes)
			)
		)
		(property "License" "Apache-2.0"
			(at 223.52 165.1 0)
			(effects
				(font
					(size 1.27 1.27)
					(thickness 0.15)
				)
				(justify left bottom)
				(hide yes)
			)
		)
		(pin "1"
		)
		(instances
			(project "jetson-orin-baseboard"
				(path ""
					(reference "#PWR0190")
					(unit 1)
				)
			)
		)
	)
	(symbol
		(lib_id "antmicropower:VCC")
		(at 166.37 162.56 0)
		(unit 1)
		(exclude_from_sim no)
		(in_bom yes)
		(on_board yes)
		(dnp no)
		(property "Reference" "#PWR0259"
			(at 166.37 166.37 0)
			(effects
				(font
					(size 1.27 1.27)
				)
				(justify left bottom)
				(hide yes)
			)
		)
		(property "Value" "VCC"
			(at 164.465 158.75 0)
			(effects
				(font
					(size 1.27 1.27)
				)
				(justify left)
			)
		)
		(property "Footprint" ""
			(at 166.37 162.56 0)
			(effects
				(font
					(size 1.27 1.27)
				)
				(hide yes)
			)
		)
		(property "Datasheet" ""
			(at 166.37 162.56 0)
			(effects
				(font
					(size 1.27 1.27)
				)
				(hide yes)
			)
		)
		(property "Description" ""
			(at 166.37 162.56 0)
			(effects
				(font
					(size 1.27 1.27)
				)
				(hide yes)
			)
		)
		(pin "1"
		)
		(instances
			(project "jetson-orin-baseboard"
				(path ""
					(reference "#PWR0259")
					(unit 1)
				)
			)
		)
	)
	(symbol
		(lib_id "antmicroTVSDiodes:ESD9X5.0ST5G")
		(at 382.27 31.75 270)
		(unit 1)
		(exclude_from_sim no)
		(in_bom yes)
		(on_board yes)
		(dnp no)
		(property "Reference" "D30"
			(at 381 33.02 90)
			(effects
				(font
					(size 1.27 1.27)
				)
				(justify right)
			)
		)
		(property "Value" "ESD9X5.0ST5G"
			(at 367.03 53.34 0)
			(effects
				(font
					(size 1.27 1.27)
					(thickness 0.15)
				)
				(justify left bottom)
				(hide yes)
			)
		)
		(property "Footprint" "antmicro-footprints:SOD-923"
			(at 374.65 53.34 0)
			(effects
				(font
					(size 1.27 1.27)
					(thickness 0.15)
				)
				(justify left bottom)
				(hide yes)
			)
		)
		(property "Datasheet" "https://www.onsemi.com/pdf/datasheet/esd9x3.3st5g-d.pdf"
			(at 372.11 53.34 0)
			(effects
				(font
					(size 1.27 1.27)
					(thickness 0.15)
				)
				(justify left bottom)
				(hide yes)
			)
		)
		(property "Description" ""
			(at 382.27 31.75 0)
			(effects
				(font
					(size 1.27 1.27)
				)
				(hide yes)
			)
		)
		(property "Manufacturer" "ON Semiconductor"
			(at 369.57 53.34 0)
			(effects
				(font
					(size 1.27 1.27)
					(thickness 0.15)
				)
				(justify left bottom)
				(hide yes)
			)
		)
		(property "MPN" "ESD9X5.0ST5G"
			(at 381 35.56 90)
			(effects
				(font
					(size 1.27 1.27)
					(thickness 0.15)
				)
				(justify right)
			)
		)
		(property "Author" "Antmicro"
			(at 364.49 53.34 0)
			(effects
				(font
					(size 1.27 1.27)
					(thickness 0.15)
				)
				(justify left bottom)
				(hide yes)
			)
		)
		(property "License" "Apache-2.0"
			(at 361.95 53.34 0)
			(effects
				(font
					(size 1.27 1.27)
					(thickness 0.15)
				)
				(justify left bottom)
				(hide yes)
			)
		)
		(pin "1"
		)
		(pin "2"
		)
		(instances
			(project "jetson-orin-baseboard"
				(path ""
					(reference "D30")
					(unit 1)
				)
			)
		)
	)
	(symbol
		(lib_id "antmicroCapacitorsmisc:C_22u_25V_0805")
		(at 189.23 147.32 90)
		(unit 1)
		(exclude_from_sim no)
		(in_bom yes)
		(on_board yes)
		(dnp no)
		(property "Reference" "C5"
			(at 189.865 142.875 90)
			(effects
				(font
					(size 1.27 1.27)
					(thickness 0.15)
				)
				(justify right)
			)
		)
		(property "Value" "C_22u_25V_0805"
			(at 199.39 127 0)
			(effects
				(font
					(size 1.27 1.27)
					(thickness 0.15)
				)
				(justify left bottom)
				(hide yes)
			)
		)
		(property "Footprint" "antmicro-footprints:C_0805_2012Metric"
			(at 201.93 127 0)
			(effects
				(font
					(size 1.27 1.27)
					(thickness 0.15)
				)
				(justify left bottom)
				(hide yes)
			)
		)
		(property "Datasheet" "https://product.samsungsem.com/mlcc/CL21A226MAYNNN.do"
			(at 204.47 127 0)
			(effects
				(font
					(size 1.27 1.27)
					(thickness 0.15)
				)
				(justify left bottom)
				(hide yes)
			)
		)
		(property "Description" ""
			(at 189.23 147.32 0)
			(effects
				(font
					(size 1.27 1.27)
				)
				(hide yes)
			)
		)
		(property "MPN" "CL21A226MAYNNNE"
			(at 207.01 127 0)
			(effects
				(font
					(size 1.27 1.27)
					(thickness 0.15)
				)
				(justify left bottom)
				(hide yes)
			)
		)
		(property "Manufacturer" "Samsung Electro-Mechanics"
			(at 209.55 127 0)
			(effects
				(font
					(size 1.27 1.27)
					(thickness 0.15)
				)
				(justify left bottom)
				(hide yes)
			)
		)
		(property "License" "Apache-2.0"
			(at 212.09 127 0)
			(effects
				(font
					(size 1.27 1.27)
					(thickness 0.15)
				)
				(justify left bottom)
				(hide yes)
			)
		)
		(property "Author" "Antmicro"
			(at 214.63 127 0)
			(effects
				(font
					(size 1.27 1.27)
					(thickness 0.15)
				)
				(justify left bottom)
				(hide yes)
			)
		)
		(property "Val" "22u"
			(at 189.865 146.685 90)
			(effects
				(font
					(size 1.27 1.27)
					(thickness 0.15)
				)
				(justify right)
			)
		)
		(property "Voltage" "25V"
			(at 189.865 149.225 90)
			(effects
				(font
					(size 1.27 1.27)
				)
				(justify right)
			)
		)
		(property "Dielectric" "X5R"
			(at 219.71 127 0)
			(effects
				(font
					(size 1.27 1.27)
				)
				(justify left bottom)
				(hide yes)
			)
		)
		(property "Public" "False"
			(at 222.25 127 0)
			(effects
				(font
					(size 1.27 1.27)
				)
				(justify left bottom)
				(hide yes)
			)
		)
		(pin "2"
		)
		(pin "1"
		)
		(instances
			(project "jetson-orin-baseboard"
				(path ""
					(reference "C5")
					(unit 1)
				)
			)
		)
	)
	(symbol
		(lib_id "antmicroCapacitors0402:C_10u_0402")
		(at 106.68 67.31 90)
		(unit 1)
		(exclude_from_sim no)
		(in_bom yes)
		(on_board yes)
		(dnp no)
		(property "Reference" "C117"
			(at 108.585 63.5 90)
			(effects
				(font
					(size 1.27 1.27)
					(thickness 0.15)
				)
				(justify right)
			)
		)
		(property "Value" "C_10u_0402"
			(at 116.84 46.99 0)
			(effects
				(font
					(size 1.27 1.27)
					(thickness 0.15)
				)
				(justify left bottom)
				(hide yes)
			)
		)
		(property "Footprint" "antmicro-footprints:C_0402_1005Metric"
			(at 119.38 46.99 0)
			(effects
				(font
					(size 1.27 1.27)
					(thickness 0.15)
				)
				(justify left bottom)
				(hide yes)
			)
		)
		(property "Datasheet" "https://www.yageo.com/en/Chart/Download/pdf/CC0402MRX5R5BB106"
			(at 121.92 46.99 0)
			(effects
				(font
					(size 1.27 1.27)
					(thickness 0.15)
				)
				(justify left bottom)
				(hide yes)
			)
		)
		(property "Description" ""
			(at 106.68 67.31 0)
			(effects
				(font
					(size 1.27 1.27)
				)
				(hide yes)
			)
		)
		(property "MPN" "CC0402MRX5R5BB106"
			(at 124.46 46.99 0)
			(effects
				(font
					(size 1.27 1.27)
					(thickness 0.15)
				)
				(justify left bottom)
				(hide yes)
			)
		)
		(property "Manufacturer" "YAGEO"
			(at 127 46.99 0)
			(effects
				(font
					(size 1.27 1.27)
					(thickness 0.15)
				)
				(justify left bottom)
				(hide yes)
			)
		)
		(property "License" "Apache-2.0"
			(at 129.54 46.99 0)
			(effects
				(font
					(size 1.27 1.27)
					(thickness 0.15)
				)
				(justify left bottom)
				(hide yes)
			)
		)
		(property "Author" "Antmicro"
			(at 132.08 46.99 0)
			(effects
				(font
					(size 1.27 1.27)
					(thickness 0.15)
				)
				(justify left bottom)
				(hide yes)
			)
		)
		(property "Val" "10u"
			(at 108.585 66.04 90)
			(effects
				(font
					(size 1.27 1.27)
					(thickness 0.15)
				)
				(justify right)
			)
		)
		(property "Voltage" ""
			(at 134.62 46.99 0)
			(effects
				(font
					(size 1.27 1.27)
				)
				(justify left bottom)
				(hide yes)
			)
		)
		(property "Dielectric" ""
			(at 137.16 46.99 0)
			(effects
				(font
					(size 1.27 1.27)
				)
				(justify left bottom)
				(hide yes)
			)
		)
		(pin "1"
		)
		(pin "2"
		)
		(instances
			(project "jetson-orin-baseboard"
				(path ""
					(reference "C117")
					(unit 1)
				)
			)
		)
	)
	(symbol
		(lib_id "antmicropower:PWR_FLAG")
		(at 355.6 190.5 0)
		(unit 1)
		(exclude_from_sim no)
		(in_bom yes)
		(on_board yes)
		(dnp no)
		(property "Reference" "#FLG06"
			(at 355.6 188.595 0)
			(effects
				(font
					(size 1.27 1.27)
				)
				(hide yes)
			)
		)
		(property "Value" "PWR_FLAG"
			(at 355.6 186.69 0)
			(effects
				(font
					(size 1.27 1.27)
				)
			)
		)
		(property "Footprint" ""
			(at 355.6 190.5 0)
			(effects
				(font
					(size 1.27 1.27)
				)
				(hide yes)
			)
		)
		(property "Datasheet" ""
			(at 355.6 190.5 0)
			(effects
				(font
					(size 1.27 1.27)
				)
				(hide yes)
			)
		)
		(property "Description" ""
			(at 355.6 190.5 0)
			(effects
				(font
					(size 1.27 1.27)
				)
				(hide yes)
			)
		)
		(pin "1"
		)
		(instances
			(project "jetson-orin-baseboard"
				(path ""
					(reference "#FLG06")
					(unit 1)
				)
			)
		)
	)
	(symbol
		(lib_id "antmicropower:GND")
		(at 242.57 213.36 0)
		(unit 1)
		(exclude_from_sim no)
		(in_bom yes)
		(on_board yes)
		(dnp no)
		(property "Reference" "#PWR0340"
			(at 242.57 219.71 0)
			(effects
				(font
					(size 1.27 1.27)
				)
				(justify left bottom)
				(hide yes)
			)
		)
		(property "Value" "GND"
			(at 242.57 217.17 0)
			(effects
				(font
					(size 1.27 1.27)
					(thickness 0.15)
				)
			)
		)
		(property "Footprint" ""
			(at 251.46 220.98 0)
			(effects
				(font
					(size 1.27 1.27)
					(thickness 0.15)
				)
				(justify left bottom)
				(hide yes)
			)
		)
		(property "Datasheet" ""
			(at 251.46 226.06 0)
			(effects
				(font
					(size 1.27 1.27)
					(thickness 0.15)
				)
				(justify left bottom)
				(hide yes)
			)
		)
		(property "Description" ""
			(at 242.57 213.36 0)
			(effects
				(font
					(size 1.27 1.27)
				)
				(hide yes)
			)
		)
		(property "Author" "Antmicro"
			(at 251.46 220.98 0)
			(effects
				(font
					(size 1.27 1.27)
					(thickness 0.15)
				)
				(justify left bottom)
				(hide yes)
			)
		)
		(property "License" "Apache-2.0"
			(at 251.46 223.52 0)
			(effects
				(font
					(size 1.27 1.27)
					(thickness 0.15)
				)
				(justify left bottom)
				(hide yes)
			)
		)
		(pin "1"
		)
		(instances
			(project "jetson-orin-baseboard"
				(path ""
					(reference "#PWR0340")
					(unit 1)
				)
			)
		)
	)
	(symbol
		(lib_id "antmicroCapacitors0402:C_4u7_25V_0402")
		(at 242.57 153.67 90)
		(unit 1)
		(exclude_from_sim no)
		(in_bom yes)
		(on_board yes)
		(dnp no)
		(property "Reference" "C156"
			(at 243.205 149.225 90)
			(effects
				(font
					(size 1.27 1.27)
					(thickness 0.15)
				)
				(justify right)
			)
		)
		(property "Value" "C_4u7_25V_0402"
			(at 252.73 133.35 0)
			(effects
				(font
					(size 1.27 1.27)
					(thickness 0.15)
				)
				(justify left bottom)
				(hide yes)
			)
		)
		(property "Footprint" "antmicro-footprints:C_0402_1005Metric"
			(at 255.27 133.35 0)
			(effects
				(font
					(size 1.27 1.27)
					(thickness 0.15)
				)
				(justify left bottom)
				(hide yes)
			)
		)
		(property "Datasheet" "https://www.murata.com/products/productdetail?partno=GRM155C61E475ME15%23"
			(at 257.81 133.35 0)
			(effects
				(font
					(size 1.27 1.27)
					(thickness 0.15)
				)
				(justify left bottom)
				(hide yes)
			)
		)
		(property "Description" ""
			(at 242.57 153.67 0)
			(effects
				(font
					(size 1.27 1.27)
				)
				(hide yes)
			)
		)
		(property "MPN" "GRM155C61E475ME15J"
			(at 260.35 133.35 0)
			(effects
				(font
					(size 1.27 1.27)
					(thickness 0.15)
				)
				(justify left bottom)
				(hide yes)
			)
		)
		(property "Manufacturer" "Murata"
			(at 262.89 133.35 0)
			(effects
				(font
					(size 1.27 1.27)
					(thickness 0.15)
				)
				(justify left bottom)
				(hide yes)
			)
		)
		(property "License" "Apache-2.0"
			(at 265.43 133.35 0)
			(effects
				(font
					(size 1.27 1.27)
					(thickness 0.15)
				)
				(justify left bottom)
				(hide yes)
			)
		)
		(property "Author" "Antmicro"
			(at 267.97 133.35 0)
			(effects
				(font
					(size 1.27 1.27)
					(thickness 0.15)
				)
				(justify left bottom)
				(hide yes)
			)
		)
		(property "Val" "4u7"
			(at 243.205 153.035 90)
			(effects
				(font
					(size 1.27 1.27)
					(thickness 0.15)
				)
				(justify right)
			)
		)
		(property "Voltage" "25V"
			(at 270.51 133.35 0)
			(effects
				(font
					(size 1.27 1.27)
				)
				(justify left bottom)
				(hide yes)
			)
		)
		(property "Dielectric" "X5S"
			(at 273.05 133.35 0)
			(effects
				(font
					(size 1.27 1.27)
				)
				(justify left bottom)
				(hide yes)
			)
		)
		(pin "2"
		)
		(pin "1"
		)
		(instances
			(project "jetson-orin-baseboard"
				(path ""
					(reference "C156")
					(unit 1)
				)
			)
		)
	)
	(symbol
		(lib_id "antmicroCapacitorsmisc:C_22u_25V_0805")
		(at 189.23 205.74 90)
		(unit 1)
		(exclude_from_sim no)
		(in_bom yes)
		(on_board yes)
		(dnp no)
		(property "Reference" "C122"
			(at 189.865 201.295 90)
			(effects
				(font
					(size 1.27 1.27)
					(thickness 0.15)
				)
				(justify right)
			)
		)
		(property "Value" "C_22u_25V_0805"
			(at 199.39 185.42 0)
			(effects
				(font
					(size 1.27 1.27)
					(thickness 0.15)
				)
				(justify left bottom)
				(hide yes)
			)
		)
		(property "Footprint" "antmicro-footprints:C_0805_2012Metric"
			(at 201.93 185.42 0)
			(effects
				(font
					(size 1.27 1.27)
					(thickness 0.15)
				)
				(justify left bottom)
				(hide yes)
			)
		)
		(property "Datasheet" "https://product.samsungsem.com/mlcc/CL21A226MAYNNN.do"
			(at 204.47 185.42 0)
			(effects
				(font
					(size 1.27 1.27)
					(thickness 0.15)
				)
				(justify left bottom)
				(hide yes)
			)
		)
		(property "Description" ""
			(at 189.23 205.74 0)
			(effects
				(font
					(size 1.27 1.27)
				)
				(hide yes)
			)
		)
		(property "MPN" "CL21A226MAYNNNE"
			(at 207.01 185.42 0)
			(effects
				(font
					(size 1.27 1.27)
					(thickness 0.15)
				)
				(justify left bottom)
				(hide yes)
			)
		)
		(property "Manufacturer" "Samsung Electro-Mechanics"
			(at 209.55 185.42 0)
			(effects
				(font
					(size 1.27 1.27)
					(thickness 0.15)
				)
				(justify left bottom)
				(hide yes)
			)
		)
		(property "License" "Apache-2.0"
			(at 212.09 185.42 0)
			(effects
				(font
					(size 1.27 1.27)
					(thickness 0.15)
				)
				(justify left bottom)
				(hide yes)
			)
		)
		(property "Author" "Antmicro"
			(at 214.63 185.42 0)
			(effects
				(font
					(size 1.27 1.27)
					(thickness 0.15)
				)
				(justify left bottom)
				(hide yes)
			)
		)
		(property "Val" "22u"
			(at 189.865 205.105 90)
			(effects
				(font
					(size 1.27 1.27)
					(thickness 0.15)
				)
				(justify right)
			)
		)
		(property "Voltage" "25V"
			(at 189.865 207.01 90)
			(effects
				(font
					(size 1.27 1.27)
				)
				(justify right)
			)
		)
		(property "Dielectric" "X5R"
			(at 219.71 185.42 0)
			(effects
				(font
					(size 1.27 1.27)
				)
				(justify left bottom)
				(hide yes)
			)
		)
		(property "Public" "False"
			(at 222.25 185.42 0)
			(effects
				(font
					(size 1.27 1.27)
				)
				(justify left bottom)
				(hide yes)
			)
		)
		(pin "2"
		)
		(pin "1"
		)
		(instances
			(project "jetson-orin-baseboard"
				(path ""
					(reference "C122")
					(unit 1)
				)
			)
		)
	)
	(symbol
		(lib_id "antmicropower:GND")
		(at 347.98 38.1 0)
		(unit 1)
		(exclude_from_sim no)
		(in_bom yes)
		(on_board yes)
		(dnp no)
		(property "Reference" "#PWR0176"
			(at 347.98 44.45 0)
			(effects
				(font
					(size 1.27 1.27)
				)
				(justify left bottom)
				(hide yes)
			)
		)
		(property "Value" "GND"
			(at 347.98 41.91 0)
			(effects
				(font
					(size 1.27 1.27)
					(thickness 0.15)
				)
			)
		)
		(property "Footprint" ""
			(at 356.87 45.72 0)
			(effects
				(font
					(size 1.27 1.27)
					(thickness 0.15)
				)
				(justify left bottom)
				(hide yes)
			)
		)
		(property "Datasheet" ""
			(at 356.87 50.8 0)
			(effects
				(font
					(size 1.27 1.27)
					(thickness 0.15)
				)
				(justify left bottom)
				(hide yes)
			)
		)
		(property "Description" ""
			(at 347.98 38.1 0)
			(effects
				(font
					(size 1.27 1.27)
				)
				(hide yes)
			)
		)
		(property "Author" "Antmicro"
			(at 356.87 45.72 0)
			(effects
				(font
					(size 1.27 1.27)
					(thickness 0.15)
				)
				(justify left bottom)
				(hide yes)
			)
		)
		(property "License" "Apache-2.0"
			(at 356.87 48.26 0)
			(effects
				(font
					(size 1.27 1.27)
					(thickness 0.15)
				)
				(justify left bottom)
				(hide yes)
			)
		)
		(pin "1"
		)
		(instances
			(project "jetson-orin-baseboard"
				(path ""
					(reference "#PWR0176")
					(unit 1)
				)
			)
		)
	)
	(symbol
		(lib_id "antmicropower:GND")
		(at 134.62 69.85 0)
		(unit 1)
		(exclude_from_sim no)
		(in_bom yes)
		(on_board yes)
		(dnp no)
		(property "Reference" "#PWR0261"
			(at 134.62 76.2 0)
			(effects
				(font
					(size 1.27 1.27)
				)
				(justify left bottom)
				(hide yes)
			)
		)
		(property "Value" "GND"
			(at 134.62 73.66 0)
			(effects
				(font
					(size 1.27 1.27)
					(thickness 0.15)
				)
			)
		)
		(property "Footprint" ""
			(at 143.51 77.47 0)
			(effects
				(font
					(size 1.27 1.27)
					(thickness 0.15)
				)
				(justify left bottom)
				(hide yes)
			)
		)
		(property "Datasheet" ""
			(at 143.51 82.55 0)
			(effects
				(font
					(size 1.27 1.27)
					(thickness 0.15)
				)
				(justify left bottom)
				(hide yes)
			)
		)
		(property "Description" ""
			(at 134.62 69.85 0)
			(effects
				(font
					(size 1.27 1.27)
				)
				(hide yes)
			)
		)
		(property "Author" "Antmicro"
			(at 143.51 77.47 0)
			(effects
				(font
					(size 1.27 1.27)
					(thickness 0.15)
				)
				(justify left bottom)
				(hide yes)
			)
		)
		(property "License" "Apache-2.0"
			(at 143.51 80.01 0)
			(effects
				(font
					(size 1.27 1.27)
					(thickness 0.15)
				)
				(justify left bottom)
				(hide yes)
			)
		)
		(pin "1"
		)
		(instances
			(project "jetson-orin-baseboard"
				(path ""
					(reference "#PWR0261")
					(unit 1)
				)
			)
		)
	)
	(symbol
		(lib_id "antmicroResistors0402:R_10k_0402")
		(at 302.26 148.59 90)
		(unit 1)
		(exclude_from_sim no)
		(in_bom yes)
		(on_board yes)
		(dnp no)
		(property "Reference" "R269"
			(at 303.53 144.78 90)
			(effects
				(font
					(size 1.27 1.27)
					(thickness 0.15)
				)
				(justify right)
			)
		)
		(property "Value" "R_10k_0402"
			(at 314.96 128.27 0)
			(effects
				(font
					(size 1.27 1.27)
					(thickness 0.15)
				)
				(justify left bottom)
				(hide yes)
			)
		)
		(property "Footprint" "antmicro-footprints:R_0402_1005Metric"
			(at 317.5 128.27 0)
			(effects
				(font
					(size 1.27 1.27)
					(thickness 0.15)
				)
				(justify left bottom)
				(hide yes)
			)
		)
		(property "Datasheet" "https://www.bourns.com/docs/product-datasheets/cr.pdf"
			(at 320.04 128.27 0)
			(effects
				(font
					(size 1.27 1.27)
					(thickness 0.15)
				)
				(justify left bottom)
				(hide yes)
			)
		)
		(property "Description" ""
			(at 302.26 148.59 0)
			(effects
				(font
					(size 1.27 1.27)
				)
				(hide yes)
			)
		)
		(property "MPN" "CR0402-FX-1002GLF"
			(at 322.58 128.27 0)
			(effects
				(font
					(size 1.27 1.27)
					(thickness 0.15)
				)
				(justify left bottom)
				(hide yes)
			)
		)
		(property "Manufacturer" "Bourns"
			(at 325.12 128.27 0)
			(effects
				(font
					(size 1.27 1.27)
					(thickness 0.15)
				)
				(justify left bottom)
				(hide yes)
			)
		)
		(property "License" "Apache-2.0"
			(at 327.66 128.27 0)
			(effects
				(font
					(size 1.27 1.27)
					(thickness 0.15)
				)
				(justify left bottom)
				(hide yes)
			)
		)
		(property "Author" "Antmicro"
			(at 330.2 128.27 0)
			(effects
				(font
					(size 1.27 1.27)
					(thickness 0.15)
				)
				(justify left bottom)
				(hide yes)
			)
		)
		(property "Val" "10k"
			(at 303.53 147.32 90)
			(effects
				(font
					(size 1.27 1.27)
					(thickness 0.15)
				)
				(justify right)
			)
		)
		(property "Tolerance" "1%"
			(at 312.42 128.27 0)
			(effects
				(font
					(size 1.27 1.27)
				)
				(justify left bottom)
				(hide yes)
			)
		)
		(pin "2"
		)
		(pin "1"
		)
		(instances
			(project "jetson-orin-baseboard"
				(path ""
					(reference "R269")
					(unit 1)
				)
			)
		)
	)
	(symbol
		(lib_id "antmicroCapacitors0603:C_22u_16V_0603")
		(at 313.69 207.01 90)
		(unit 1)
		(exclude_from_sim no)
		(in_bom yes)
		(on_board yes)
		(dnp no)
		(property "Reference" "C126"
			(at 314.325 202.565 90)
			(effects
				(font
					(size 1.27 1.27)
				)
				(justify right)
			)
		)
		(property "Value" "C_22u_16V_0603"
			(at 323.85 186.69 0)
			(effects
				(font
					(size 1.27 1.27)
					(thickness 0.15)
				)
				(justify left bottom)
				(hide yes)
			)
		)
		(property "Footprint" "antmicro-footprints:C_0603_1608Metric_EIA"
			(at 326.39 186.69 0)
			(effects
				(font
					(size 1.27 1.27)
					(thickness 0.15)
				)
				(justify left bottom)
				(hide yes)
			)
		)
		(property "Datasheet" "https://product.samsungsem.com/mlcc/CL10A226MO7JZN.do"
			(at 328.93 186.69 0)
			(effects
				(font
					(size 1.27 1.27)
					(thickness 0.15)
				)
				(justify left bottom)
				(hide yes)
			)
		)
		(property "Description" "SMD Multilayer Ceramic Capacitor"
			(at 313.69 207.01 0)
			(effects
				(font
					(size 1.27 1.27)
				)
				(hide yes)
			)
		)
		(property "Manufacturer" "Samsung Electro-Mechanics"
			(at 334.01 186.69 0)
			(effects
				(font
					(size 1.27 1.27)
					(thickness 0.15)
				)
				(justify left bottom)
				(hide yes)
			)
		)
		(property "MPN" "CL10A226MO7JZNC"
			(at 331.47 186.69 0)
			(effects
				(font
					(size 1.27 1.27)
					(thickness 0.15)
				)
				(justify left bottom)
				(hide yes)
			)
		)
		(property "Val" "22u"
			(at 314.325 206.375 90)
			(effects
				(font
					(size 1.27 1.27)
					(thickness 0.15)
				)
				(justify right)
			)
		)
		(property "License" "Apache-2.0"
			(at 336.55 186.69 0)
			(effects
				(font
					(size 1.27 1.27)
					(thickness 0.15)
				)
				(justify left bottom)
				(hide yes)
			)
		)
		(property "Author" "Antmicro"
			(at 339.09 186.69 0)
			(effects
				(font
					(size 1.27 1.27)
					(thickness 0.15)
				)
				(justify left bottom)
				(hide yes)
			)
		)
		(property "Voltage" "16V"
			(at 341.63 186.69 0)
			(effects
				(font
					(size 1.27 1.27)
				)
				(justify left bottom)
				(hide yes)
			)
		)
		(property "Dielectric" ""
			(at 344.17 186.69 0)
			(effects
				(font
					(size 1.27 1.27)
				)
				(justify left bottom)
				(hide yes)
			)
		)
		(pin "1"
		)
		(pin "2"
		)
		(instances
			(project "jetson-orin-baseboard"
				(path ""
					(reference "C126")
					(unit 1)
				)
			)
		)
	)
	(symbol
		(lib_id "antmicropower:GND")
		(at 182.88 60.96 0)
		(unit 1)
		(exclude_from_sim no)
		(in_bom yes)
		(on_board yes)
		(dnp no)
		(property "Reference" "#PWR0264"
			(at 182.88 67.31 0)
			(effects
				(font
					(size 1.27 1.27)
				)
				(justify left bottom)
				(hide yes)
			)
		)
		(property "Value" "GND"
			(at 182.88 64.77 0)
			(effects
				(font
					(size 1.27 1.27)
					(thickness 0.15)
				)
			)
		)
		(property "Footprint" ""
			(at 191.77 68.58 0)
			(effects
				(font
					(size 1.27 1.27)
					(thickness 0.15)
				)
				(justify left bottom)
				(hide yes)
			)
		)
		(property "Datasheet" ""
			(at 191.77 73.66 0)
			(effects
				(font
					(size 1.27 1.27)
					(thickness 0.15)
				)
				(justify left bottom)
				(hide yes)
			)
		)
		(property "Description" ""
			(at 182.88 60.96 0)
			(effects
				(font
					(size 1.27 1.27)
				)
				(hide yes)
			)
		)
		(property "Author" "Antmicro"
			(at 191.77 68.58 0)
			(effects
				(font
					(size 1.27 1.27)
					(thickness 0.15)
				)
				(justify left bottom)
				(hide yes)
			)
		)
		(property "License" "Apache-2.0"
			(at 191.77 71.12 0)
			(effects
				(font
					(size 1.27 1.27)
					(thickness 0.15)
				)
				(justify left bottom)
				(hide yes)
			)
		)
		(pin "1"
		)
		(instances
			(project "jetson-orin-baseboard"
				(path ""
					(reference "#PWR0264")
					(unit 1)
				)
			)
		)
	)
	(symbol
		(lib_id "antmicropower:GND")
		(at 274.32 213.36 0)
		(unit 1)
		(exclude_from_sim no)
		(in_bom yes)
		(on_board yes)
		(dnp no)
		(property "Reference" "#PWR0336"
			(at 274.32 219.71 0)
			(effects
				(font
					(size 1.27 1.27)
				)
				(justify left bottom)
				(hide yes)
			)
		)
		(property "Value" "GND"
			(at 274.32 217.17 0)
			(effects
				(font
					(size 1.27 1.27)
					(thickness 0.15)
				)
			)
		)
		(property "Footprint" ""
			(at 283.21 220.98 0)
			(effects
				(font
					(size 1.27 1.27)
					(thickness 0.15)
				)
				(justify left bottom)
				(hide yes)
			)
		)
		(property "Datasheet" ""
			(at 283.21 226.06 0)
			(effects
				(font
					(size 1.27 1.27)
					(thickness 0.15)
				)
				(justify left bottom)
				(hide yes)
			)
		)
		(property "Description" ""
			(at 274.32 213.36 0)
			(effects
				(font
					(size 1.27 1.27)
				)
				(hide yes)
			)
		)
		(property "Author" "Antmicro"
			(at 283.21 220.98 0)
			(effects
				(font
					(size 1.27 1.27)
					(thickness 0.15)
				)
				(justify left bottom)
				(hide yes)
			)
		)
		(property "License" "Apache-2.0"
			(at 283.21 223.52 0)
			(effects
				(font
					(size 1.27 1.27)
					(thickness 0.15)
				)
				(justify left bottom)
				(hide yes)
			)
		)
		(pin "1"
		)
		(instances
			(project "jetson-orin-baseboard"
				(path ""
					(reference "#PWR0336")
					(unit 1)
				)
			)
		)
	)
	(symbol
		(lib_id "antmicropower:GND")
		(at 382.27 38.1 0)
		(unit 1)
		(exclude_from_sim no)
		(in_bom yes)
		(on_board yes)
		(dnp no)
		(property "Reference" "#PWR0251"
			(at 382.27 44.45 0)
			(effects
				(font
					(size 1.27 1.27)
				)
				(justify left bottom)
				(hide yes)
			)
		)
		(property "Value" "GND"
			(at 382.27 41.91 0)
			(effects
				(font
					(size 1.27 1.27)
					(thickness 0.15)
				)
			)
		)
		(property "Footprint" ""
			(at 391.16 45.72 0)
			(effects
				(font
					(size 1.27 1.27)
					(thickness 0.15)
				)
				(justify left bottom)
				(hide yes)
			)
		)
		(property "Datasheet" ""
			(at 391.16 50.8 0)
			(effects
				(font
					(size 1.27 1.27)
					(thickness 0.15)
				)
				(justify left bottom)
				(hide yes)
			)
		)
		(property "Description" ""
			(at 382.27 38.1 0)
			(effects
				(font
					(size 1.27 1.27)
				)
				(hide yes)
			)
		)
		(property "Author" "Antmicro"
			(at 391.16 45.72 0)
			(effects
				(font
					(size 1.27 1.27)
					(thickness 0.15)
				)
				(justify left bottom)
				(hide yes)
			)
		)
		(property "License" "Apache-2.0"
			(at 391.16 48.26 0)
			(effects
				(font
					(size 1.27 1.27)
					(thickness 0.15)
				)
				(justify left bottom)
				(hide yes)
			)
		)
		(pin "1"
		)
		(instances
			(project "jetson-orin-baseboard"
				(path ""
					(reference "#PWR0251")
					(unit 1)
				)
			)
		)
	)
	(symbol
		(lib_id "antmicropower:GND")
		(at 336.55 213.36 0)
		(unit 1)
		(exclude_from_sim no)
		(in_bom yes)
		(on_board yes)
		(dnp no)
		(property "Reference" "#PWR0348"
			(at 336.55 219.71 0)
			(effects
				(font
					(size 1.27 1.27)
				)
				(justify left bottom)
				(hide yes)
			)
		)
		(property "Value" "GND"
			(at 336.55 217.17 0)
			(effects
				(font
					(size 1.27 1.27)
					(thickness 0.15)
				)
			)
		)
		(property "Footprint" ""
			(at 345.44 220.98 0)
			(effects
				(font
					(size 1.27 1.27)
					(thickness 0.15)
				)
				(justify left bottom)
				(hide yes)
			)
		)
		(property "Datasheet" ""
			(at 345.44 226.06 0)
			(effects
				(font
					(size 1.27 1.27)
					(thickness 0.15)
				)
				(justify left bottom)
				(hide yes)
			)
		)
		(property "Description" ""
			(at 336.55 213.36 0)
			(effects
				(font
					(size 1.27 1.27)
				)
				(hide yes)
			)
		)
		(property "Author" "Antmicro"
			(at 345.44 220.98 0)
			(effects
				(font
					(size 1.27 1.27)
					(thickness 0.15)
				)
				(justify left bottom)
				(hide yes)
			)
		)
		(property "License" "Apache-2.0"
			(at 345.44 223.52 0)
			(effects
				(font
					(size 1.27 1.27)
					(thickness 0.15)
				)
				(justify left bottom)
				(hide yes)
			)
		)
		(pin "1"
		)
		(instances
			(project "jetson-orin-baseboard"
				(path ""
					(reference "#PWR0348")
					(unit 1)
				)
			)
		)
	)
	(symbol
		(lib_id "antmicropower:GND")
		(at 267.97 57.15 0)
		(unit 1)
		(exclude_from_sim no)
		(in_bom yes)
		(on_board yes)
		(dnp no)
		(property "Reference" "#PWR0269"
			(at 267.97 63.5 0)
			(effects
				(font
					(size 1.27 1.27)
				)
				(justify left bottom)
				(hide yes)
			)
		)
		(property "Value" "GND"
			(at 267.97 60.96 0)
			(effects
				(font
					(size 1.27 1.27)
					(thickness 0.15)
				)
			)
		)
		(property "Footprint" ""
			(at 276.86 64.77 0)
			(effects
				(font
					(size 1.27 1.27)
					(thickness 0.15)
				)
				(justify left bottom)
				(hide yes)
			)
		)
		(property "Datasheet" ""
			(at 276.86 69.85 0)
			(effects
				(font
					(size 1.27 1.27)
					(thickness 0.15)
				)
				(justify left bottom)
				(hide yes)
			)
		)
		(property "Description" ""
			(at 267.97 57.15 0)
			(effects
				(font
					(size 1.27 1.27)
				)
				(hide yes)
			)
		)
		(property "Author" "Antmicro"
			(at 276.86 64.77 0)
			(effects
				(font
					(size 1.27 1.27)
					(thickness 0.15)
				)
				(justify left bottom)
				(hide yes)
			)
		)
		(property "License" "Apache-2.0"
			(at 276.86 67.31 0)
			(effects
				(font
					(size 1.27 1.27)
					(thickness 0.15)
				)
				(justify left bottom)
				(hide yes)
			)
		)
		(pin "1"
		)
		(instances
			(project "jetson-orin-baseboard"
				(path ""
					(reference "#PWR0269")
					(unit 1)
				)
			)
		)
	)
	(symbol
		(lib_id "antmicroTestPoints:TP_0.75mm_SMD")
		(at 383.54 27.94 0)
		(unit 1)
		(exclude_from_sim no)
		(in_bom no)
		(on_board yes)
		(dnp no)
		(property "Reference" "TP52"
			(at 387.35 27.94 0)
			(effects
				(font
					(size 1.27 1.27)
				)
				(justify left)
			)
		)
		(property "Value" "TP_0.75mm_SMD"
			(at 393.7 31.75 0)
			(effects
				(font
					(size 1.27 1.27)
					(thickness 0.15)
				)
				(justify left bottom)
				(hide yes)
			)
		)
		(property "Footprint" "antmicro-footprints:TP_SMD_0.75mm"
			(at 393.7 34.29 0)
			(effects
				(font
					(size 1.27 1.27)
					(thickness 0.15)
				)
				(justify left bottom)
				(hide yes)
			)
		)
		(property "Datasheet" ""
			(at 401.32 40.64 0)
			(effects
				(font
					(size 1.27 1.27)
					(thickness 0.15)
				)
				(justify left bottom)
				(hide yes)
			)
		)
		(property "Description" ""
			(at 383.54 27.94 0)
			(effects
				(font
					(size 1.27 1.27)
				)
				(hide yes)
			)
		)
		(property "MPN" ""
			(at 394.335 39.37 0)
			(effects
				(font
					(size 1.27 1.27)
					(thickness 0.15)
				)
				(justify left bottom)
				(hide yes)
			)
		)
		(property "Manufacturer" ""
			(at 394.335 34.29 0)
			(effects
				(font
					(size 1.27 1.27)
					(thickness 0.15)
				)
				(justify left bottom)
				(hide yes)
			)
		)
		(property "Author" "Antmicro"
			(at 393.7 36.83 0)
			(effects
				(font
					(size 1.27 1.27)
					(thickness 0.15)
				)
				(justify left bottom)
				(hide yes)
			)
		)
		(property "License" "Apache-2.0"
			(at 393.7 39.37 0)
			(effects
				(font
					(size 1.27 1.27)
					(thickness 0.15)
				)
				(justify left bottom)
				(hide yes)
			)
		)
		(pin "1"
		)
		(instances
			(project "jetson-orin-baseboard"
				(path ""
					(reference "TP52")
					(unit 1)
				)
			)
		)
	)
	(symbol
		(lib_id "antmicropower:GND")
		(at 213.36 250.19 0)
		(unit 1)
		(exclude_from_sim no)
		(in_bom yes)
		(on_board yes)
		(dnp no)
		(property "Reference" "#PWR0368"
			(at 213.36 256.54 0)
			(effects
				(font
					(size 1.27 1.27)
				)
				(justify left bottom)
				(hide yes)
			)
		)
		(property "Value" "GND"
			(at 213.36 254 0)
			(effects
				(font
					(size 1.27 1.27)
					(thickness 0.15)
				)
			)
		)
		(property "Footprint" ""
			(at 222.25 257.81 0)
			(effects
				(font
					(size 1.27 1.27)
					(thickness 0.15)
				)
				(justify left bottom)
				(hide yes)
			)
		)
		(property "Datasheet" ""
			(at 222.25 262.89 0)
			(effects
				(font
					(size 1.27 1.27)
					(thickness 0.15)
				)
				(justify left bottom)
				(hide yes)
			)
		)
		(property "Description" ""
			(at 213.36 250.19 0)
			(effects
				(font
					(size 1.27 1.27)
				)
				(hide yes)
			)
		)
		(property "Author" "Antmicro"
			(at 222.25 257.81 0)
			(effects
				(font
					(size 1.27 1.27)
					(thickness 0.15)
				)
				(justify left bottom)
				(hide yes)
			)
		)
		(property "License" "Apache-2.0"
			(at 222.25 260.35 0)
			(effects
				(font
					(size 1.27 1.27)
					(thickness 0.15)
				)
				(justify left bottom)
				(hide yes)
			)
		)
		(pin "1"
		)
		(instances
			(project "jetson-orin-baseboard"
				(path ""
					(reference "#PWR0368")
					(unit 1)
				)
			)
		)
	)
	(symbol
		(lib_id "antmicroCapacitors0402:C_1u_0402")
		(at 233.68 212.09 90)
		(unit 1)
		(exclude_from_sim no)
		(in_bom yes)
		(on_board yes)
		(dnp no)
		(property "Reference" "C123"
			(at 234.315 207.645 90)
			(effects
				(font
					(size 1.27 1.27)
				)
				(justify right)
			)
		)
		(property "Value" "C_1u_0402"
			(at 243.84 191.77 0)
			(effects
				(font
					(size 1.27 1.27)
					(thickness 0.15)
				)
				(justify left bottom)
				(hide yes)
			)
		)
		(property "Footprint" "antmicro-footprints:C_0402_1005Metric"
			(at 246.38 191.77 0)
			(effects
				(font
					(size 1.27 1.27)
					(thickness 0.15)
				)
				(justify left bottom)
				(hide yes)
			)
		)
		(property "Datasheet" "https://product.tdk.com/en/search/capacitor/ceramic/mlcc/info?part_no=C1005X6S1A105K050BC"
			(at 248.92 191.77 0)
			(effects
				(font
					(size 1.27 1.27)
					(thickness 0.15)
				)
				(justify left bottom)
				(hide yes)
			)
		)
		(property "Description" ""
			(at 233.68 212.09 0)
			(effects
				(font
					(size 1.27 1.27)
				)
				(hide yes)
			)
		)
		(property "Manufacturer" "TDK"
			(at 254 191.77 0)
			(effects
				(font
					(size 1.27 1.27)
					(thickness 0.15)
				)
				(justify left bottom)
				(hide yes)
			)
		)
		(property "MPN" "C1005X6S1A105K050BC"
			(at 251.46 191.77 0)
			(effects
				(font
					(size 1.27 1.27)
					(thickness 0.15)
				)
				(justify left bottom)
				(hide yes)
			)
		)
		(property "Val" "1u"
			(at 234.315 211.455 90)
			(effects
				(font
					(size 1.27 1.27)
					(thickness 0.15)
				)
				(justify right)
			)
		)
		(property "License" "Apache-2.0"
			(at 256.54 191.77 0)
			(effects
				(font
					(size 1.27 1.27)
					(thickness 0.15)
				)
				(justify left bottom)
				(hide yes)
			)
		)
		(property "Author" "Antmicro"
			(at 259.08 191.77 0)
			(effects
				(font
					(size 1.27 1.27)
					(thickness 0.15)
				)
				(justify left bottom)
				(hide yes)
			)
		)
		(property "Voltage" ""
			(at 261.62 191.77 0)
			(effects
				(font
					(size 1.27 1.27)
				)
				(justify left bottom)
				(hide yes)
			)
		)
		(property "Dielectric" ""
			(at 264.16 191.77 0)
			(effects
				(font
					(size 1.27 1.27)
				)
				(justify left bottom)
				(hide yes)
			)
		)
		(pin "1"
		)
		(pin "2"
		)
		(instances
			(project "jetson-orin-baseboard"
				(path ""
					(reference "C123")
					(unit 1)
				)
			)
		)
	)
	(symbol
		(lib_id "antmicropower:GND")
		(at 302.26 213.36 0)
		(unit 1)
		(exclude_from_sim no)
		(in_bom yes)
		(on_board yes)
		(dnp no)
		(property "Reference" "#PWR0341"
			(at 302.26 219.71 0)
			(effects
				(font
					(size 1.27 1.27)
				)
				(justify left bottom)
				(hide yes)
			)
		)
		(property "Value" "GND"
			(at 302.26 217.17 0)
			(effects
				(font
					(size 1.27 1.27)
					(thickness 0.15)
				)
			)
		)
		(property "Footprint" ""
			(at 311.15 220.98 0)
			(effects
				(font
					(size 1.27 1.27)
					(thickness 0.15)
				)
				(justify left bottom)
				(hide yes)
			)
		)
		(property "Datasheet" ""
			(at 311.15 226.06 0)
			(effects
				(font
					(size 1.27 1.27)
					(thickness 0.15)
				)
				(justify left bottom)
				(hide yes)
			)
		)
		(property "Description" ""
			(at 302.26 213.36 0)
			(effects
				(font
					(size 1.27 1.27)
				)
				(hide yes)
			)
		)
		(property "Author" "Antmicro"
			(at 311.15 220.98 0)
			(effects
				(font
					(size 1.27 1.27)
					(thickness 0.15)
				)
				(justify left bottom)
				(hide yes)
			)
		)
		(property "License" "Apache-2.0"
			(at 311.15 223.52 0)
			(effects
				(font
					(size 1.27 1.27)
					(thickness 0.15)
				)
				(justify left bottom)
				(hide yes)
			)
		)
		(pin "1"
		)
		(instances
			(project "jetson-orin-baseboard"
				(path ""
					(reference "#PWR0341")
					(unit 1)
				)
			)
		)
	)
	(symbol
		(lib_id "antmicroResistors0402:R_10k_0402")
		(at 50.8 152.4 90)
		(unit 1)
		(exclude_from_sim no)
		(in_bom yes)
		(on_board yes)
		(dnp no)
		(property "Reference" "R250"
			(at 52.07 148.59 90)
			(effects
				(font
					(size 1.27 1.27)
				)
				(justify right)
			)
		)
		(property "Value" "R_10k_0402"
			(at 63.5 132.08 0)
			(effects
				(font
					(size 1.27 1.27)
					(thickness 0.15)
				)
				(justify left bottom)
				(hide yes)
			)
		)
		(property "Footprint" "antmicro-footprints:R_0402_1005Metric"
			(at 66.04 132.08 0)
			(effects
				(font
					(size 1.27 1.27)
					(thickness 0.15)
				)
				(justify left bottom)
				(hide yes)
			)
		)
		(property "Datasheet" "https://www.bourns.com/docs/product-datasheets/cr.pdf"
			(at 68.58 132.08 0)
			(effects
				(font
					(size 1.27 1.27)
					(thickness 0.15)
				)
				(justify left bottom)
				(hide yes)
			)
		)
		(property "Description" ""
			(at 50.8 152.4 0)
			(effects
				(font
					(size 1.27 1.27)
				)
				(hide yes)
			)
		)
		(property "Manufacturer" "Bourns"
			(at 73.66 132.08 0)
			(effects
				(font
					(size 1.27 1.27)
					(thickness 0.15)
				)
				(justify left bottom)
				(hide yes)
			)
		)
		(property "MPN" "CR0402-FX-1002GLF"
			(at 71.12 132.08 0)
			(effects
				(font
					(size 1.27 1.27)
					(thickness 0.15)
				)
				(justify left bottom)
				(hide yes)
			)
		)
		(property "Val" "10k"
			(at 52.07 151.13 90)
			(effects
				(font
					(size 1.27 1.27)
					(thickness 0.15)
				)
				(justify right)
			)
		)
		(property "License" "Apache-2.0"
			(at 76.2 132.08 0)
			(effects
				(font
					(size 1.27 1.27)
					(thickness 0.15)
				)
				(justify left bottom)
				(hide yes)
			)
		)
		(property "Author" "Antmicro"
			(at 78.74 132.08 0)
			(effects
				(font
					(size 1.27 1.27)
					(thickness 0.15)
				)
				(justify left bottom)
				(hide yes)
			)
		)
		(property "Tolerance" "1%"
			(at 60.96 132.08 0)
			(effects
				(font
					(size 1.27 1.27)
				)
				(justify left bottom)
				(hide yes)
			)
		)
		(pin "1"
		)
		(pin "2"
		)
		(instances
			(project "jetson-orin-baseboard"
				(path ""
					(reference "R250")
					(unit 1)
				)
			)
		)
	)
	(symbol
		(lib_id "antmicropower:+5V")
		(at 162.56 241.3 0)
		(unit 1)
		(exclude_from_sim no)
		(in_bom yes)
		(on_board yes)
		(dnp no)
		(property "Reference" "#PWR0376"
			(at 162.56 245.11 0)
			(effects
				(font
					(size 1.27 1.27)
				)
				(justify left bottom)
				(hide yes)
			)
		)
		(property "Value" "+5V_SoM"
			(at 162.56 237.49 0)
			(effects
				(font
					(size 1.27 1.27)
					(thickness 0.15)
				)
			)
		)
		(property "Footprint" ""
			(at 177.8 248.92 0)
			(effects
				(font
					(size 1.27 1.27)
					(thickness 0.15)
				)
				(justify left bottom)
				(hide yes)
			)
		)
		(property "Datasheet" ""
			(at 177.8 251.46 0)
			(effects
				(font
					(size 1.27 1.27)
					(thickness 0.15)
				)
				(justify left bottom)
				(hide yes)
			)
		)
		(property "Description" ""
			(at 162.56 241.3 0)
			(effects
				(font
					(size 1.27 1.27)
				)
				(hide yes)
			)
		)
		(property "Author" "Antmicro"
			(at 177.8 248.92 0)
			(effects
				(font
					(size 1.27 1.27)
					(thickness 0.15)
				)
				(justify left bottom)
				(hide yes)
			)
		)
		(property "License" "Apache-2.0"
			(at 177.8 251.46 0)
			(effects
				(font
					(size 1.27 1.27)
					(thickness 0.15)
				)
				(justify left bottom)
				(hide yes)
			)
		)
		(pin "1"
		)
		(instances
			(project "jetson-orin-baseboard"
				(path ""
					(reference "#PWR0376")
					(unit 1)
				)
			)
		)
	)
	(symbol
		(lib_id "antmicroCapacitors0402:C_1u_0402")
		(at 233.68 153.67 90)
		(unit 1)
		(exclude_from_sim no)
		(in_bom yes)
		(on_board yes)
		(dnp no)
		(property "Reference" "C93"
			(at 234.315 149.225 90)
			(effects
				(font
					(size 1.27 1.27)
				)
				(justify right)
			)
		)
		(property "Value" "C_1u_0402"
			(at 243.84 133.35 0)
			(effects
				(font
					(size 1.27 1.27)
					(thickness 0.15)
				)
				(justify left bottom)
				(hide yes)
			)
		)
		(property "Footprint" "antmicro-footprints:C_0402_1005Metric"
			(at 246.38 133.35 0)
			(effects
				(font
					(size 1.27 1.27)
					(thickness 0.15)
				)
				(justify left bottom)
				(hide yes)
			)
		)
		(property "Datasheet" "https://product.tdk.com/en/search/capacitor/ceramic/mlcc/info?part_no=C1005X6S1A105K050BC"
			(at 248.92 133.35 0)
			(effects
				(font
					(size 1.27 1.27)
					(thickness 0.15)
				)
				(justify left bottom)
				(hide yes)
			)
		)
		(property "Description" ""
			(at 233.68 153.67 0)
			(effects
				(font
					(size 1.27 1.27)
				)
				(hide yes)
			)
		)
		(property "Manufacturer" "TDK"
			(at 254 133.35 0)
			(effects
				(font
					(size 1.27 1.27)
					(thickness 0.15)
				)
				(justify left bottom)
				(hide yes)
			)
		)
		(property "MPN" "C1005X6S1A105K050BC"
			(at 251.46 133.35 0)
			(effects
				(font
					(size 1.27 1.27)
					(thickness 0.15)
				)
				(justify left bottom)
				(hide yes)
			)
		)
		(property "Val" "1u"
			(at 234.315 153.035 90)
			(effects
				(font
					(size 1.27 1.27)
					(thickness 0.15)
				)
				(justify right)
			)
		)
		(property "License" "Apache-2.0"
			(at 256.54 133.35 0)
			(effects
				(font
					(size 1.27 1.27)
					(thickness 0.15)
				)
				(justify left bottom)
				(hide yes)
			)
		)
		(property "Author" "Antmicro"
			(at 259.08 133.35 0)
			(effects
				(font
					(size 1.27 1.27)
					(thickness 0.15)
				)
				(justify left bottom)
				(hide yes)
			)
		)
		(property "Voltage" ""
			(at 261.62 133.35 0)
			(effects
				(font
					(size 1.27 1.27)
				)
				(justify left bottom)
				(hide yes)
			)
		)
		(property "Dielectric" ""
			(at 264.16 133.35 0)
			(effects
				(font
					(size 1.27 1.27)
				)
				(justify left bottom)
				(hide yes)
			)
		)
		(pin "1"
		)
		(pin "2"
		)
		(instances
			(project "jetson-orin-baseboard"
				(path ""
					(reference "C93")
					(unit 1)
				)
			)
		)
	)
	(symbol
		(lib_id "antmicropower:GND")
		(at 226.06 57.15 0)
		(unit 1)
		(exclude_from_sim no)
		(in_bom yes)
		(on_board yes)
		(dnp no)
		(property "Reference" "#PWR0252"
			(at 226.06 63.5 0)
			(effects
				(font
					(size 1.27 1.27)
				)
				(justify left bottom)
				(hide yes)
			)
		)
		(property "Value" "GND"
			(at 226.06 60.96 0)
			(effects
				(font
					(size 1.27 1.27)
					(thickness 0.15)
				)
			)
		)
		(property "Footprint" ""
			(at 234.95 64.77 0)
			(effects
				(font
					(size 1.27 1.27)
					(thickness 0.15)
				)
				(justify left bottom)
				(hide yes)
			)
		)
		(property "Datasheet" ""
			(at 234.95 69.85 0)
			(effects
				(font
					(size 1.27 1.27)
					(thickness 0.15)
				)
				(justify left bottom)
				(hide yes)
			)
		)
		(property "Description" ""
			(at 226.06 57.15 0)
			(effects
				(font
					(size 1.27 1.27)
				)
				(hide yes)
			)
		)
		(property "Author" "Antmicro"
			(at 234.95 64.77 0)
			(effects
				(font
					(size 1.27 1.27)
					(thickness 0.15)
				)
				(justify left bottom)
				(hide yes)
			)
		)
		(property "License" "Apache-2.0"
			(at 234.95 67.31 0)
			(effects
				(font
					(size 1.27 1.27)
					(thickness 0.15)
				)
				(justify left bottom)
				(hide yes)
			)
		)
		(pin "1"
		)
		(instances
			(project "jetson-orin-baseboard"
				(path ""
					(reference "#PWR0252")
					(unit 1)
				)
			)
		)
	)
	(symbol
		(lib_id "antmicropower:GND")
		(at 30.48 125.73 0)
		(unit 1)
		(exclude_from_sim no)
		(in_bom yes)
		(on_board yes)
		(dnp no)
		(property "Reference" "#PWR0250"
			(at 30.48 132.08 0)
			(effects
				(font
					(size 1.27 1.27)
				)
				(justify left bottom)
				(hide yes)
			)
		)
		(property "Value" "GND"
			(at 30.48 129.54 0)
			(effects
				(font
					(size 1.27 1.27)
					(thickness 0.15)
				)
			)
		)
		(property "Footprint" ""
			(at 39.37 133.35 0)
			(effects
				(font
					(size 1.27 1.27)
					(thickness 0.15)
				)
				(justify left bottom)
				(hide yes)
			)
		)
		(property "Datasheet" ""
			(at 39.37 138.43 0)
			(effects
				(font
					(size 1.27 1.27)
					(thickness 0.15)
				)
				(justify left bottom)
				(hide yes)
			)
		)
		(property "Description" ""
			(at 30.48 125.73 0)
			(effects
				(font
					(size 1.27 1.27)
				)
				(hide yes)
			)
		)
		(property "Author" "Antmicro"
			(at 39.37 133.35 0)
			(effects
				(font
					(size 1.27 1.27)
					(thickness 0.15)
				)
				(justify left bottom)
				(hide yes)
			)
		)
		(property "License" "Apache-2.0"
			(at 39.37 135.89 0)
			(effects
				(font
					(size 1.27 1.27)
					(thickness 0.15)
				)
				(justify left bottom)
				(hide yes)
			)
		)
		(pin "1"
		)
		(instances
			(project "jetson-orin-baseboard"
				(path ""
					(reference "#PWR0250")
					(unit 1)
				)
			)
		)
	)
	(symbol
		(lib_id "antmicropower:GND")
		(at 302.26 154.94 0)
		(unit 1)
		(exclude_from_sim no)
		(in_bom yes)
		(on_board yes)
		(dnp no)
		(property "Reference" "#PWR0187"
			(at 302.26 161.29 0)
			(effects
				(font
					(size 1.27 1.27)
				)
				(justify left bottom)
				(hide yes)
			)
		)
		(property "Value" "GND"
			(at 302.26 158.75 0)
			(effects
				(font
					(size 1.27 1.27)
					(thickness 0.15)
				)
			)
		)
		(property "Footprint" ""
			(at 311.15 162.56 0)
			(effects
				(font
					(size 1.27 1.27)
					(thickness 0.15)
				)
				(justify left bottom)
				(hide yes)
			)
		)
		(property "Datasheet" ""
			(at 311.15 167.64 0)
			(effects
				(font
					(size 1.27 1.27)
					(thickness 0.15)
				)
				(justify left bottom)
				(hide yes)
			)
		)
		(property "Description" ""
			(at 302.26 154.94 0)
			(effects
				(font
					(size 1.27 1.27)
				)
				(hide yes)
			)
		)
		(property "Author" "Antmicro"
			(at 311.15 162.56 0)
			(effects
				(font
					(size 1.27 1.27)
					(thickness 0.15)
				)
				(justify left bottom)
				(hide yes)
			)
		)
		(property "License" "Apache-2.0"
			(at 311.15 165.1 0)
			(effects
				(font
					(size 1.27 1.27)
					(thickness 0.15)
				)
				(justify left bottom)
				(hide yes)
			)
		)
		(pin "1"
		)
		(instances
			(project "jetson-orin-baseboard"
				(path ""
					(reference "#PWR0187")
					(unit 1)
				)
			)
		)
	)
	(symbol
		(lib_id "antmicroCapacitors0402:C_100n_0402")
		(at 172.72 33.02 90)
		(unit 1)
		(exclude_from_sim no)
		(in_bom yes)
		(on_board yes)
		(dnp no)
		(fields_autoplaced yes)
		(property "Reference" "C119"
			(at 175.26 29.2036 90)
			(effects
				(font
					(size 1.27 1.27)
				)
				(justify right)
			)
		)
		(property "Value" "C_100n_0402"
			(at 182.88 12.7 0)
			(effects
				(font
					(size 1.27 1.27)
					(thickness 0.15)
				)
				(justify left bottom)
				(hide yes)
			)
		)
		(property "Footprint" "antmicro-footprints:C_0402_1005Metric"
			(at 185.42 12.7 0)
			(effects
				(font
					(size 1.27 1.27)
					(thickness 0.15)
				)
				(justify left bottom)
				(hide yes)
			)
		)
		(property "Datasheet" "https://www.murata.com/products/productdetail?partno=GRM155R61H104KE14%23"
			(at 187.96 12.7 0)
			(effects
				(font
					(size 1.27 1.27)
					(thickness 0.15)
				)
				(justify left bottom)
				(hide yes)
			)
		)
		(property "Description" ""
			(at 172.72 33.02 0)
			(effects
				(font
					(size 1.27 1.27)
				)
				(hide yes)
			)
		)
		(property "Manufacturer" "Murata"
			(at 193.04 12.7 0)
			(effects
				(font
					(size 1.27 1.27)
					(thickness 0.15)
				)
				(justify left bottom)
				(hide yes)
			)
		)
		(property "MPN" "GRM155R61H104KE14D"
			(at 190.5 12.7 0)
			(effects
				(font
					(size 1.27 1.27)
					(thickness 0.15)
				)
				(justify left bottom)
				(hide yes)
			)
		)
		(property "Val" "100n"
			(at 175.26 31.7436 90)
			(effects
				(font
					(size 1.27 1.27)
					(thickness 0.15)
				)
				(justify right)
			)
		)
		(property "License" "Apache-2.0"
			(at 195.58 12.7 0)
			(effects
				(font
					(size 1.27 1.27)
					(thickness 0.15)
				)
				(justify left bottom)
				(hide yes)
			)
		)
		(property "Author" "Antmicro"
			(at 198.12 12.7 0)
			(effects
				(font
					(size 1.27 1.27)
					(thickness 0.15)
				)
				(justify left bottom)
				(hide yes)
			)
		)
		(property "Voltage" "50V"
			(at 200.66 12.7 0)
			(effects
				(font
					(size 1.27 1.27)
				)
				(justify left bottom)
				(hide yes)
			)
		)
		(property "Dielectric" "X5R"
			(at 203.2 12.7 0)
			(effects
				(font
					(size 1.27 1.27)
				)
				(justify left bottom)
				(hide yes)
			)
		)
		(pin "1"
		)
		(pin "2"
		)
		(instances
			(project "jetson-orin-baseboard"
				(path ""
					(reference "C119")
					(unit 1)
				)
			)
		)
	)
	(symbol
		(lib_id "antmicroSlideSwitches:SW_SPDT_PCM12SMTR")
		(at 80.01 59.69 0)
		(mirror y)
		(unit 1)
		(exclude_from_sim no)
		(in_bom yes)
		(on_board yes)
		(dnp no)
		(property "Reference" "SW1"
			(at 73.66 52.07 0)
			(effects
				(font
					(size 1.27 1.27)
				)
			)
		)
		(property "Value" "SW_SPDT_PCM12SMTR"
			(at 73.66 54.61 0)
			(effects
				(font
					(size 1.27 1.27)
					(thickness 0.15)
				)
			)
		)
		(property "Footprint" "antmicro-footprints:PCM12SMTR"
			(at 52.07 69.85 0)
			(effects
				(font
					(size 1.27 1.27)
					(thickness 0.15)
				)
				(justify left bottom)
				(hide yes)
			)
		)
		(property "Datasheet" "https://www.mouser.com/datasheet/2/60/pcm-1841544.pdf"
			(at 52.07 72.39 0)
			(effects
				(font
					(size 1.27 1.27)
					(thickness 0.15)
				)
				(justify left bottom)
				(hide yes)
			)
		)
		(property "Description" ""
			(at 80.01 59.69 0)
			(effects
				(font
					(size 1.27 1.27)
				)
				(hide yes)
			)
		)
		(property "Manufacturer" "C&K"
			(at 52.07 74.93 0)
			(effects
				(font
					(size 1.27 1.27)
					(thickness 0.15)
				)
				(justify left bottom)
				(hide yes)
			)
		)
		(property "MPN" "PCM12SMTR"
			(at 52.07 77.47 0)
			(effects
				(font
					(size 1.27 1.27)
					(thickness 0.15)
				)
				(justify left bottom)
				(hide yes)
			)
		)
		(property "Author" "Antmicro"
			(at 52.07 80.01 0)
			(effects
				(font
					(size 1.27 1.27)
					(thickness 0.15)
				)
				(justify left bottom)
				(hide yes)
			)
		)
		(property "License" "Apache-2.0"
			(at 52.07 82.55 0)
			(effects
				(font
					(size 1.27 1.27)
					(thickness 0.15)
				)
				(justify left bottom)
				(hide yes)
			)
		)
		(pin "1"
		)
		(pin "2"
		)
		(pin "3"
		)
		(pin "S1"
		)
		(pin "S2"
		)
		(pin "S3"
		)
		(pin "S4"
		)
		(instances
			(project "jetson-orin-baseboard"
				(path ""
					(reference "SW1")
					(unit 1)
				)
			)
		)
	)
	(symbol
		(lib_id "antmicroResistors0402:R_560R_0402")
		(at 241.3 278.13 90)
		(unit 1)
		(exclude_from_sim no)
		(in_bom yes)
		(on_board yes)
		(dnp no)
		(fields_autoplaced yes)
		(property "Reference" "R283"
			(at 243.84 274.32 90)
			(effects
				(font
					(size 1.27 1.27)
					(thickness 0.15)
				)
				(justify right)
			)
		)
		(property "Value" "R_560R_0402"
			(at 254 257.81 0)
			(effects
				(font
					(size 1.27 1.27)
					(thickness 0.15)
				)
				(justify left bottom)
				(hide yes)
			)
		)
		(property "Footprint" "antmicro-footprints:R_0402_1005Metric"
			(at 256.54 257.81 0)
			(effects
				(font
					(size 1.27 1.27)
					(thickness 0.15)
				)
				(justify left bottom)
				(hide yes)
			)
		)
		(property "Datasheet" "https://www.bourns.com/docs/product-datasheets/cr.pdf"
			(at 259.08 257.81 0)
			(effects
				(font
					(size 1.27 1.27)
					(thickness 0.15)
				)
				(justify left bottom)
				(hide yes)
			)
		)
		(property "Description" "SMD Chip Resistor, 560 ohm, ± 1%, 100 mW, 0402 [1005 Metric], Thick Film, Precision"
			(at 241.3 278.13 0)
			(effects
				(font
					(size 1.27 1.27)
				)
				(hide yes)
			)
		)
		(property "MPN" "CR0402-FX-5600GLF"
			(at 261.62 257.81 0)
			(effects
				(font
					(size 1.27 1.27)
					(thickness 0.15)
				)
				(justify left bottom)
				(hide yes)
			)
		)
		(property "Manufacturer" "Bourns"
			(at 264.16 257.81 0)
			(effects
				(font
					(size 1.27 1.27)
					(thickness 0.15)
				)
				(justify left bottom)
				(hide yes)
			)
		)
		(property "License" "Apache-2.0"
			(at 266.7 257.81 0)
			(effects
				(font
					(size 1.27 1.27)
					(thickness 0.15)
				)
				(justify left bottom)
				(hide yes)
			)
		)
		(property "Author" "Antmicro"
			(at 269.24 257.81 0)
			(effects
				(font
					(size 1.27 1.27)
					(thickness 0.15)
				)
				(justify left bottom)
				(hide yes)
			)
		)
		(property "Val" "560R"
			(at 243.84 276.86 90)
			(effects
				(font
					(size 1.27 1.27)
					(thickness 0.15)
				)
				(justify right)
			)
		)
		(property "Tolerance" "1%"
			(at 251.46 257.81 0)
			(effects
				(font
					(size 1.27 1.27)
				)
				(justify left bottom)
				(hide yes)
			)
		)
		(pin "1"
		)
		(pin "2"
		)
		(instances
			(project ""
				(path ""
					(reference "R283")
					(unit 1)
				)
			)
		)
	)
	(symbol
		(lib_id "antmicroResistors0402:R_10k_0402")
		(at 50.8 199.39 90)
		(unit 1)
		(exclude_from_sim no)
		(in_bom yes)
		(on_board yes)
		(dnp no)
		(property "Reference" "R251"
			(at 52.07 195.58 90)
			(effects
				(font
					(size 1.27 1.27)
				)
				(justify right)
			)
		)
		(property "Value" "R_10k_0402"
			(at 63.5 179.07 0)
			(effects
				(font
					(size 1.27 1.27)
					(thickness 0.15)
				)
				(justify left bottom)
				(hide yes)
			)
		)
		(property "Footprint" "antmicro-footprints:R_0402_1005Metric"
			(at 66.04 179.07 0)
			(effects
				(font
					(size 1.27 1.27)
					(thickness 0.15)
				)
				(justify left bottom)
				(hide yes)
			)
		)
		(property "Datasheet" "https://www.bourns.com/docs/product-datasheets/cr.pdf"
			(at 68.58 179.07 0)
			(effects
				(font
					(size 1.27 1.27)
					(thickness 0.15)
				)
				(justify left bottom)
				(hide yes)
			)
		)
		(property "Description" ""
			(at 50.8 199.39 0)
			(effects
				(font
					(size 1.27 1.27)
				)
				(hide yes)
			)
		)
		(property "Manufacturer" "Bourns"
			(at 73.66 179.07 0)
			(effects
				(font
					(size 1.27 1.27)
					(thickness 0.15)
				)
				(justify left bottom)
				(hide yes)
			)
		)
		(property "MPN" "CR0402-FX-1002GLF"
			(at 71.12 179.07 0)
			(effects
				(font
					(size 1.27 1.27)
					(thickness 0.15)
				)
				(justify left bottom)
				(hide yes)
			)
		)
		(property "Val" "10k"
			(at 52.07 198.12 90)
			(effects
				(font
					(size 1.27 1.27)
					(thickness 0.15)
				)
				(justify right)
			)
		)
		(property "License" "Apache-2.0"
			(at 76.2 179.07 0)
			(effects
				(font
					(size 1.27 1.27)
					(thickness 0.15)
				)
				(justify left bottom)
				(hide yes)
			)
		)
		(property "Author" "Antmicro"
			(at 78.74 179.07 0)
			(effects
				(font
					(size 1.27 1.27)
					(thickness 0.15)
				)
				(justify left bottom)
				(hide yes)
			)
		)
		(property "Tolerance" "1%"
			(at 60.96 179.07 0)
			(effects
				(font
					(size 1.27 1.27)
				)
				(justify left bottom)
				(hide yes)
			)
		)
		(pin "1"
		)
		(pin "2"
		)
		(instances
			(project "jetson-orin-baseboard"
				(path ""
					(reference "R251")
					(unit 1)
				)
			)
		)
	)
	(symbol
		(lib_id "antmicroResistors0402:R_100k_0402")
		(at 254 245.11 0)
		(mirror x)
		(unit 1)
		(exclude_from_sim no)
		(in_bom yes)
		(on_board yes)
		(dnp no)
		(property "Reference" "R274"
			(at 251.968 243.84 0)
			(effects
				(font
					(size 1.27 1.27)
				)
			)
		)
		(property "Value" "R_100k_0402"
			(at 274.32 232.41 0)
			(effects
				(font
					(size 1.27 1.27)
					(thickness 0.15)
				)
				(justify left bottom)
				(hide yes)
			)
		)
		(property "Footprint" "antmicro-footprints:R_0402_1005Metric"
			(at 274.32 229.87 0)
			(effects
				(font
					(size 1.27 1.27)
					(thickness 0.15)
				)
				(justify left bottom)
				(hide yes)
			)
		)
		(property "Datasheet" "https://www.bourns.com/docs/product-datasheets/cr.pdf"
			(at 274.32 227.33 0)
			(effects
				(font
					(size 1.27 1.27)
					(thickness 0.15)
				)
				(justify left bottom)
				(hide yes)
			)
		)
		(property "Description" ""
			(at 254 245.11 0)
			(effects
				(font
					(size 1.27 1.27)
				)
				(hide yes)
			)
		)
		(property "Manufacturer" "Bourns"
			(at 274.32 222.25 0)
			(effects
				(font
					(size 1.27 1.27)
					(thickness 0.15)
				)
				(justify left bottom)
				(hide yes)
			)
		)
		(property "MPN" "CR0402-FX-1003GLF"
			(at 274.32 224.79 0)
			(effects
				(font
					(size 1.27 1.27)
					(thickness 0.15)
				)
				(justify left bottom)
				(hide yes)
			)
		)
		(property "Val" "100k"
			(at 251.968 246.38 0)
			(effects
				(font
					(size 1.27 1.27)
					(thickness 0.15)
				)
			)
		)
		(property "License" "Apache-2.0"
			(at 274.32 219.71 0)
			(effects
				(font
					(size 1.27 1.27)
					(thickness 0.15)
				)
				(justify left bottom)
				(hide yes)
			)
		)
		(property "Author" "Antmicro"
			(at 274.32 217.17 0)
			(effects
				(font
					(size 1.27 1.27)
					(thickness 0.15)
				)
				(justify left bottom)
				(hide yes)
			)
		)
		(property "Tolerance" "1%"
			(at 274.32 234.95 0)
			(effects
				(font
					(size 1.27 1.27)
				)
				(justify left bottom)
				(hide yes)
			)
		)
		(pin "1"
		)
		(pin "2"
		)
		(instances
			(project "jetson-orin-baseboard"
				(path ""
					(reference "R274")
					(unit 1)
				)
			)
		)
	)
	(symbol
		(lib_id "antmicroWire2BoardConnectors:Molex_Nano-Fit_1x2_SMD_1054301202")
		(at 29.21 118.11 0)
		(mirror y)
		(unit 1)
		(exclude_from_sim no)
		(in_bom yes)
		(on_board yes)
		(dnp no)
		(property "Reference" "J12"
			(at 24.765 111.76 0)
			(effects
				(font
					(size 1.27 1.27)
				)
			)
		)
		(property "Value" "Molex_Nano-Fit_1x2_SMD_1054301202"
			(at 2.54 125.73 0)
			(effects
				(font
					(size 1.27 1.27)
					(thickness 0.15)
				)
				(justify left bottom)
				(hide yes)
			)
		)
		(property "Footprint" "antmicro-footprints:Conn_Molex_Nano-Fit_1x2_SMD_1054301202"
			(at 2.54 128.27 0)
			(effects
				(font
					(size 1.27 1.27)
					(thickness 0.15)
				)
				(justify left bottom)
				(hide yes)
			)
		)
		(property "Datasheet" "https://www.farnell.com/cad/3578051.pdf"
			(at 2.54 130.81 0)
			(effects
				(font
					(size 1.27 1.27)
					(thickness 0.15)
				)
				(justify left bottom)
				(hide yes)
			)
		)
		(property "Description" ""
			(at 29.21 118.11 0)
			(effects
				(font
					(size 1.27 1.27)
				)
				(hide yes)
			)
		)
		(property "Manufacturer" "Molex"
			(at 2.54 133.35 0)
			(effects
				(font
					(size 1.27 1.27)
					(thickness 0.15)
				)
				(justify left bottom)
				(hide yes)
			)
		)
		(property "MPN" "105430-1202"
			(at 24.765 114.3 0)
			(effects
				(font
					(size 1.27 1.27)
					(thickness 0.15)
				)
			)
		)
		(property "Author" "Antmicro"
			(at 2.54 135.89 0)
			(effects
				(font
					(size 1.27 1.27)
					(thickness 0.15)
				)
				(justify left bottom)
				(hide yes)
			)
		)
		(property "License" "Apache-2.0"
			(at 2.54 138.43 0)
			(effects
				(font
					(size 1.27 1.27)
					(thickness 0.15)
				)
				(justify left bottom)
				(hide yes)
			)
		)
		(pin "1"
		)
		(pin "2"
		)
		(pin "MP"
		)
		(instances
			(project "jetson-orin-baseboard"
				(path ""
					(reference "J12")
					(unit 1)
				)
			)
		)
	)
	(symbol
		(lib_id "antmicropower:PWR_FLAG")
		(at 156.21 162.56 0)
		(unit 1)
		(exclude_from_sim no)
		(in_bom yes)
		(on_board yes)
		(dnp no)
		(property "Reference" "#FLG011"
			(at 156.21 160.655 0)
			(effects
				(font
					(size 1.27 1.27)
				)
				(hide yes)
			)
		)
		(property "Value" "PWR_FLAG"
			(at 156.21 158.75 0)
			(effects
				(font
					(size 1.27 1.27)
				)
			)
		)
		(property "Footprint" ""
			(at 156.21 162.56 0)
			(effects
				(font
					(size 1.27 1.27)
				)
				(hide yes)
			)
		)
		(property "Datasheet" ""
			(at 156.21 162.56 0)
			(effects
				(font
					(size 1.27 1.27)
				)
				(hide yes)
			)
		)
		(property "Description" ""
			(at 156.21 162.56 0)
			(effects
				(font
					(size 1.27 1.27)
				)
				(hide yes)
			)
		)
		(pin "1"
		)
		(instances
			(project "jetson-orin-baseboard"
				(path ""
					(reference "#FLG011")
					(unit 1)
				)
			)
		)
	)
	(symbol
		(lib_id "antmicropower:GND")
		(at 355.6 78.74 0)
		(unit 1)
		(exclude_from_sim no)
		(in_bom yes)
		(on_board yes)
		(dnp no)
		(property "Reference" "#PWR064"
			(at 355.6 85.09 0)
			(effects
				(font
					(size 1.27 1.27)
				)
				(justify left bottom)
				(hide yes)
			)
		)
		(property "Value" "GND"
			(at 355.6 82.55 0)
			(effects
				(font
					(size 1.27 1.27)
					(thickness 0.15)
				)
			)
		)
		(property "Footprint" ""
			(at 364.49 86.36 0)
			(effects
				(font
					(size 1.27 1.27)
					(thickness 0.15)
				)
				(justify left bottom)
				(hide yes)
			)
		)
		(property "Datasheet" ""
			(at 364.49 91.44 0)
			(effects
				(font
					(size 1.27 1.27)
					(thickness 0.15)
				)
				(justify left bottom)
				(hide yes)
			)
		)
		(property "Description" ""
			(at 355.6 78.74 0)
			(effects
				(font
					(size 1.27 1.27)
				)
				(hide yes)
			)
		)
		(property "Author" "Antmicro"
			(at 364.49 86.36 0)
			(effects
				(font
					(size 1.27 1.27)
					(thickness 0.15)
				)
				(justify left bottom)
				(hide yes)
			)
		)
		(property "License" "Apache-2.0"
			(at 364.49 88.9 0)
			(effects
				(font
					(size 1.27 1.27)
					(thickness 0.15)
				)
				(justify left bottom)
				(hide yes)
			)
		)
		(pin "1"
		)
		(instances
			(project "jetson-orin-baseboard"
				(path ""
					(reference "#PWR064")
					(unit 1)
				)
			)
		)
	)
	(symbol
		(lib_id "antmicroCapacitors0603:C_22u_16V_0603")
		(at 336.55 207.01 90)
		(unit 1)
		(exclude_from_sim no)
		(in_bom yes)
		(on_board yes)
		(dnp no)
		(property "Reference" "C154"
			(at 337.185 202.565 90)
			(effects
				(font
					(size 1.27 1.27)
				)
				(justify right)
			)
		)
		(property "Value" "C_22u_16V_0603"
			(at 346.71 186.69 0)
			(effects
				(font
					(size 1.27 1.27)
					(thickness 0.15)
				)
				(justify left bottom)
				(hide yes)
			)
		)
		(property "Footprint" "antmicro-footprints:C_0603_1608Metric_EIA"
			(at 349.25 186.69 0)
			(effects
				(font
					(size 1.27 1.27)
					(thickness 0.15)
				)
				(justify left bottom)
				(hide yes)
			)
		)
		(property "Datasheet" "https://product.samsungsem.com/mlcc/CL10A226MO7JZN.do"
			(at 351.79 186.69 0)
			(effects
				(font
					(size 1.27 1.27)
					(thickness 0.15)
				)
				(justify left bottom)
				(hide yes)
			)
		)
		(property "Description" "SMD Multilayer Ceramic Capacitor"
			(at 336.55 207.01 0)
			(effects
				(font
					(size 1.27 1.27)
				)
				(hide yes)
			)
		)
		(property "Manufacturer" "Samsung Electro-Mechanics"
			(at 356.87 186.69 0)
			(effects
				(font
					(size 1.27 1.27)
					(thickness 0.15)
				)
				(justify left bottom)
				(hide yes)
			)
		)
		(property "MPN" "CL10A226MO7JZNC"
			(at 354.33 186.69 0)
			(effects
				(font
					(size 1.27 1.27)
					(thickness 0.15)
				)
				(justify left bottom)
				(hide yes)
			)
		)
		(property "Val" "22u"
			(at 337.185 206.375 90)
			(effects
				(font
					(size 1.27 1.27)
					(thickness 0.15)
				)
				(justify right)
			)
		)
		(property "License" "Apache-2.0"
			(at 359.41 186.69 0)
			(effects
				(font
					(size 1.27 1.27)
					(thickness 0.15)
				)
				(justify left bottom)
				(hide yes)
			)
		)
		(property "Author" "Antmicro"
			(at 361.95 186.69 0)
			(effects
				(font
					(size 1.27 1.27)
					(thickness 0.15)
				)
				(justify left bottom)
				(hide yes)
			)
		)
		(property "Voltage" "16V"
			(at 364.49 186.69 0)
			(effects
				(font
					(size 1.27 1.27)
				)
				(justify left bottom)
				(hide yes)
			)
		)
		(property "Dielectric" ""
			(at 367.03 186.69 0)
			(effects
				(font
					(size 1.27 1.27)
				)
				(justify left bottom)
				(hide yes)
			)
		)
		(pin "1"
		)
		(pin "2"
		)
		(instances
			(project "jetson-orin-baseboard"
				(path ""
					(reference "C154")
					(unit 1)
				)
			)
		)
	)
	(symbol
		(lib_id "antmicroTransistorsFETsMOSFETsSingle:SSM3J332R")
		(at 374.65 142.24 270)
		(mirror x)
		(unit 1)
		(exclude_from_sim no)
		(in_bom yes)
		(on_board yes)
		(dnp no)
		(fields_autoplaced yes)
		(property "Reference" "Q6"
			(at 377.19 128.27 90)
			(effects
				(font
					(size 1.27 1.27)
				)
			)
		)
		(property "Value" "SSM3J332R"
			(at 372.11 128.27 0)
			(effects
				(font
					(size 1.27 1.27)
					(thickness 0.15)
				)
				(justify left bottom)
				(hide yes)
			)
		)
		(property "Footprint" "antmicro-footprints:SOT-23-3"
			(at 369.57 128.27 0)
			(effects
				(font
					(size 1.27 1.27)
					(thickness 0.15)
				)
				(justify left bottom)
				(hide yes)
			)
		)
		(property "Datasheet" "https://www.mouser.com/datasheet/2/408/SSM3J332R_datasheet_en_20181015-1150575.pdf"
			(at 367.03 128.27 0)
			(effects
				(font
					(size 1.27 1.27)
					(thickness 0.15)
				)
				(justify left bottom)
				(hide yes)
			)
		)
		(property "Description" ""
			(at 374.65 142.24 0)
			(effects
				(font
					(size 1.27 1.27)
				)
				(hide yes)
			)
		)
		(property "MPN" "SSM3J332R,LF"
			(at 377.19 130.81 90)
			(effects
				(font
					(size 1.27 1.27)
					(thickness 0.15)
				)
			)
		)
		(property "Manufacturer" "Toshiba"
			(at 361.95 128.27 0)
			(effects
				(font
					(size 1.27 1.27)
					(thickness 0.15)
				)
				(justify left bottom)
				(hide yes)
			)
		)
		(property "Author" "Antmicro"
			(at 359.41 128.27 0)
			(effects
				(font
					(size 1.27 1.27)
					(thickness 0.15)
				)
				(justify left bottom)
				(hide yes)
			)
		)
		(property "License" "Apache-2.0"
			(at 356.87 128.27 0)
			(effects
				(font
					(size 1.27 1.27)
					(thickness 0.15)
				)
				(justify left bottom)
				(hide yes)
			)
		)
		(pin "1"
		)
		(pin "2"
		)
		(pin "3"
		)
		(instances
			(project "jetson-orin-baseboard"
				(path ""
					(reference "Q6")
					(unit 1)
				)
			)
		)
	)
	(symbol
		(lib_id "antmicropower:VCC")
		(at 213.36 233.68 0)
		(unit 1)
		(exclude_from_sim no)
		(in_bom yes)
		(on_board yes)
		(dnp no)
		(property "Reference" "#PWR0366"
			(at 213.36 237.49 0)
			(effects
				(font
					(size 1.27 1.27)
				)
				(justify left bottom)
				(hide yes)
			)
		)
		(property "Value" "VCC"
			(at 211.455 229.87 0)
			(effects
				(font
					(size 1.27 1.27)
				)
				(justify left)
			)
		)
		(property "Footprint" ""
			(at 213.36 233.68 0)
			(effects
				(font
					(size 1.27 1.27)
				)
				(hide yes)
			)
		)
		(property "Datasheet" ""
			(at 213.36 233.68 0)
			(effects
				(font
					(size 1.27 1.27)
				)
				(hide yes)
			)
		)
		(property "Description" ""
			(at 213.36 233.68 0)
			(effects
				(font
					(size 1.27 1.27)
				)
				(hide yes)
			)
		)
		(pin "1"
		)
		(instances
			(project "jetson-orin-baseboard"
				(path ""
					(reference "#PWR0366")
					(unit 1)
				)
			)
		)
	)
	(symbol
		(lib_id "antmicropower:GND")
		(at 386.08 78.74 0)
		(unit 1)
		(exclude_from_sim no)
		(in_bom yes)
		(on_board yes)
		(dnp no)
		(property "Reference" "#PWR0143"
			(at 386.08 85.09 0)
			(effects
				(font
					(size 1.27 1.27)
				)
				(justify left bottom)
				(hide yes)
			)
		)
		(property "Value" "GND"
			(at 386.08 82.55 0)
			(effects
				(font
					(size 1.27 1.27)
					(thickness 0.15)
				)
			)
		)
		(property "Footprint" ""
			(at 394.97 86.36 0)
			(effects
				(font
					(size 1.27 1.27)
					(thickness 0.15)
				)
				(justify left bottom)
				(hide yes)
			)
		)
		(property "Datasheet" ""
			(at 394.97 91.44 0)
			(effects
				(font
					(size 1.27 1.27)
					(thickness 0.15)
				)
				(justify left bottom)
				(hide yes)
			)
		)
		(property "Description" ""
			(at 386.08 78.74 0)
			(effects
				(font
					(size 1.27 1.27)
				)
				(hide yes)
			)
		)
		(property "Author" "Antmicro"
			(at 394.97 86.36 0)
			(effects
				(font
					(size 1.27 1.27)
					(thickness 0.15)
				)
				(justify left bottom)
				(hide yes)
			)
		)
		(property "License" "Apache-2.0"
			(at 394.97 88.9 0)
			(effects
				(font
					(size 1.27 1.27)
					(thickness 0.15)
				)
				(justify left bottom)
				(hide yes)
			)
		)
		(pin "1"
		)
		(instances
			(project "jetson-orin-baseboard"
				(path ""
					(reference "#PWR0143")
					(unit 1)
				)
			)
		)
	)
	(symbol
		(lib_id "antmicroCapacitors0402:C_100n_0402")
		(at 207.01 142.24 270)
		(unit 1)
		(exclude_from_sim no)
		(in_bom yes)
		(on_board yes)
		(dnp no)
		(property "Reference" "C6"
			(at 207.645 142.875 90)
			(effects
				(font
					(size 1.27 1.27)
				)
				(justify left)
			)
		)
		(property "Value" "C_100n_0402"
			(at 196.85 162.56 0)
			(effects
				(font
					(size 1.27 1.27)
					(thickness 0.15)
				)
				(justify left bottom)
				(hide yes)
			)
		)
		(property "Footprint" "antmicro-footprints:C_0402_1005Metric"
			(at 194.31 162.56 0)
			(effects
				(font
					(size 1.27 1.27)
					(thickness 0.15)
				)
				(justify left bottom)
				(hide yes)
			)
		)
		(property "Datasheet" "https://www.murata.com/products/productdetail?partno=GRM155R61H104KE14%23"
			(at 191.77 162.56 0)
			(effects
				(font
					(size 1.27 1.27)
					(thickness 0.15)
				)
				(justify left bottom)
				(hide yes)
			)
		)
		(property "Description" ""
			(at 207.01 142.24 0)
			(effects
				(font
					(size 1.27 1.27)
				)
				(hide yes)
			)
		)
		(property "Manufacturer" "Murata"
			(at 186.69 162.56 0)
			(effects
				(font
					(size 1.27 1.27)
					(thickness 0.15)
				)
				(justify left bottom)
				(hide yes)
			)
		)
		(property "MPN" "GRM155R61H104KE14D"
			(at 189.23 162.56 0)
			(effects
				(font
					(size 1.27 1.27)
					(thickness 0.15)
				)
				(justify left bottom)
				(hide yes)
			)
		)
		(property "Val" "100n"
			(at 207.645 146.685 90)
			(effects
				(font
					(size 1.27 1.27)
					(thickness 0.15)
				)
				(justify left)
			)
		)
		(property "License" "Apache-2.0"
			(at 184.15 162.56 0)
			(effects
				(font
					(size 1.27 1.27)
					(thickness 0.15)
				)
				(justify left bottom)
				(hide yes)
			)
		)
		(property "Author" "Antmicro"
			(at 181.61 162.56 0)
			(effects
				(font
					(size 1.27 1.27)
					(thickness 0.15)
				)
				(justify left bottom)
				(hide yes)
			)
		)
		(property "Voltage" "50V"
			(at 179.07 162.56 0)
			(effects
				(font
					(size 1.27 1.27)
				)
				(justify left bottom)
				(hide yes)
			)
		)
		(property "Dielectric" "X5R"
			(at 176.53 162.56 0)
			(effects
				(font
					(size 1.27 1.27)
				)
				(justify left bottom)
				(hide yes)
			)
		)
		(pin "1"
		)
		(pin "2"
		)
		(instances
			(project "jetson-orin-baseboard"
				(path ""
					(reference "C6")
					(unit 1)
				)
			)
		)
	)
	(symbol
		(lib_id "antmicropower:+5V")
		(at 386.08 116.84 0)
		(unit 1)
		(exclude_from_sim no)
		(in_bom yes)
		(on_board yes)
		(dnp no)
		(property "Reference" "#PWR0267"
			(at 386.08 120.65 0)
			(effects
				(font
					(size 1.27 1.27)
				)
				(justify left bottom)
				(hide yes)
			)
		)
		(property "Value" "+5V"
			(at 383.54 113.03 0)
			(effects
				(font
					(size 1.27 1.27)
					(thickness 0.15)
				)
				(justify left)
			)
		)
		(property "Footprint" ""
			(at 401.32 124.46 0)
			(effects
				(font
					(size 1.27 1.27)
					(thickness 0.15)
				)
				(justify left bottom)
				(hide yes)
			)
		)
		(property "Datasheet" ""
			(at 401.32 127 0)
			(effects
				(font
					(size 1.27 1.27)
					(thickness 0.15)
				)
				(justify left bottom)
				(hide yes)
			)
		)
		(property "Description" ""
			(at 386.08 116.84 0)
			(effects
				(font
					(size 1.27 1.27)
				)
				(hide yes)
			)
		)
		(property "Author" "Antmicro"
			(at 401.32 124.46 0)
			(effects
				(font
					(size 1.27 1.27)
					(thickness 0.15)
				)
				(justify left bottom)
				(hide yes)
			)
		)
		(property "License" "Apache-2.0"
			(at 401.32 127 0)
			(effects
				(font
					(size 1.27 1.27)
					(thickness 0.15)
				)
				(justify left bottom)
				(hide yes)
			)
		)
		(pin "1"
		)
		(instances
			(project "jetson-orin-baseboard"
				(path ""
					(reference "#PWR0267")
					(unit 1)
				)
			)
		)
	)
	(symbol
		(lib_id "antmicroResistors0402:R_200k_0402")
		(at 226.06 55.88 90)
		(unit 1)
		(exclude_from_sim no)
		(in_bom yes)
		(on_board yes)
		(dnp no)
		(property "Reference" "R261"
			(at 227.33 52.07 90)
			(effects
				(font
					(size 1.27 1.27)
				)
				(justify right)
			)
		)
		(property "Value" "R_200k_0402"
			(at 238.76 35.56 0)
			(effects
				(font
					(size 1.27 1.27)
					(thickness 0.15)
				)
				(justify left bottom)
				(hide yes)
			)
		)
		(property "Footprint" "antmicro-footprints:R_0402_1005Metric"
			(at 241.3 35.56 0)
			(effects
				(font
					(size 1.27 1.27)
					(thickness 0.15)
				)
				(justify left bottom)
				(hide yes)
			)
		)
		(property "Datasheet" "https://www.bourns.com/docs/product-datasheets/cr.pdf"
			(at 243.84 35.56 0)
			(effects
				(font
					(size 1.27 1.27)
					(thickness 0.15)
				)
				(justify left bottom)
				(hide yes)
			)
		)
		(property "Description" ""
			(at 226.06 55.88 0)
			(effects
				(font
					(size 1.27 1.27)
				)
				(hide yes)
			)
		)
		(property "Manufacturer" "Bourns"
			(at 248.92 35.56 0)
			(effects
				(font
					(size 1.27 1.27)
					(thickness 0.15)
				)
				(justify left bottom)
				(hide yes)
			)
		)
		(property "MPN" "CR0402-FX-2003GLF"
			(at 246.38 35.56 0)
			(effects
				(font
					(size 1.27 1.27)
					(thickness 0.15)
				)
				(justify left bottom)
				(hide yes)
			)
		)
		(property "Val" "200k"
			(at 227.33 54.61 90)
			(effects
				(font
					(size 1.27 1.27)
					(thickness 0.15)
				)
				(justify right)
			)
		)
		(property "License" "Apache-2.0"
			(at 251.46 35.56 0)
			(effects
				(font
					(size 1.27 1.27)
					(thickness 0.15)
				)
				(justify left bottom)
				(hide yes)
			)
		)
		(property "Author" "Antmicro"
			(at 254 35.56 0)
			(effects
				(font
					(size 1.27 1.27)
					(thickness 0.15)
				)
				(justify left bottom)
				(hide yes)
			)
		)
		(property "Tolerance" "1%"
			(at 236.22 35.56 0)
			(effects
				(font
					(size 1.27 1.27)
				)
				(justify left bottom)
				(hide yes)
			)
		)
		(pin "1"
		)
		(pin "2"
		)
		(instances
			(project "jetson-orin-baseboard"
				(path ""
					(reference "R261")
					(unit 1)
				)
			)
		)
	)
	(symbol
		(lib_id "antmicroTestPoints:TP_0.75mm_SMD")
		(at 168.91 165.1 0)
		(unit 1)
		(exclude_from_sim no)
		(in_bom no)
		(on_board yes)
		(dnp no)
		(property "Reference" "TP14"
			(at 172.72 165.1 0)
			(effects
				(font
					(size 1.27 1.27)
				)
				(justify left)
			)
		)
		(property "Value" "TP_0.75mm_SMD"
			(at 179.07 168.91 0)
			(effects
				(font
					(size 1.27 1.27)
					(thickness 0.15)
				)
				(justify left bottom)
				(hide yes)
			)
		)
		(property "Footprint" "antmicro-footprints:TP_SMD_0.75mm"
			(at 179.07 171.45 0)
			(effects
				(font
					(size 1.27 1.27)
					(thickness 0.15)
				)
				(justify left bottom)
				(hide yes)
			)
		)
		(property "Datasheet" ""
			(at 186.69 177.8 0)
			(effects
				(font
					(size 1.27 1.27)
					(thickness 0.15)
				)
				(justify left bottom)
				(hide yes)
			)
		)
		(property "Description" ""
			(at 168.91 165.1 0)
			(effects
				(font
					(size 1.27 1.27)
				)
				(hide yes)
			)
		)
		(property "MPN" ""
			(at 179.705 176.53 0)
			(effects
				(font
					(size 1.27 1.27)
					(thickness 0.15)
				)
				(justify left bottom)
				(hide yes)
			)
		)
		(property "Manufacturer" ""
			(at 179.705 171.45 0)
			(effects
				(font
					(size 1.27 1.27)
					(thickness 0.15)
				)
				(justify left bottom)
				(hide yes)
			)
		)
		(property "Author" "Antmicro"
			(at 179.07 173.99 0)
			(effects
				(font
					(size 1.27 1.27)
					(thickness 0.15)
				)
				(justify left bottom)
				(hide yes)
			)
		)
		(property "License" "Apache-2.0"
			(at 179.07 176.53 0)
			(effects
				(font
					(size 1.27 1.27)
					(thickness 0.15)
				)
				(justify left bottom)
				(hide yes)
			)
		)
		(pin "1"
		)
		(instances
			(project "jetson-orin-baseboard"
				(path ""
					(reference "TP14")
					(unit 1)
				)
			)
		)
	)
	(symbol
		(lib_id "antmicropower:GND")
		(at 328.93 154.94 0)
		(unit 1)
		(exclude_from_sim no)
		(in_bom yes)
		(on_board yes)
		(dnp no)
		(property "Reference" "#PWR0196"
			(at 328.93 161.29 0)
			(effects
				(font
					(size 1.27 1.27)
				)
				(justify left bottom)
				(hide yes)
			)
		)
		(property "Value" "GND"
			(at 328.93 158.75 0)
			(effects
				(font
					(size 1.27 1.27)
					(thickness 0.15)
				)
			)
		)
		(property "Footprint" ""
			(at 337.82 162.56 0)
			(effects
				(font
					(size 1.27 1.27)
					(thickness 0.15)
				)
				(justify left bottom)
				(hide yes)
			)
		)
		(property "Datasheet" ""
			(at 337.82 167.64 0)
			(effects
				(font
					(size 1.27 1.27)
					(thickness 0.15)
				)
				(justify left bottom)
				(hide yes)
			)
		)
		(property "Description" ""
			(at 328.93 154.94 0)
			(effects
				(font
					(size 1.27 1.27)
				)
				(hide yes)
			)
		)
		(property "Author" "Antmicro"
			(at 337.82 162.56 0)
			(effects
				(font
					(size 1.27 1.27)
					(thickness 0.15)
				)
				(justify left bottom)
				(hide yes)
			)
		)
		(property "License" "Apache-2.0"
			(at 337.82 165.1 0)
			(effects
				(font
					(size 1.27 1.27)
					(thickness 0.15)
				)
				(justify left bottom)
				(hide yes)
			)
		)
		(pin "1"
		)
		(instances
			(project "jetson-orin-baseboard"
				(path ""
					(reference "#PWR0196")
					(unit 1)
				)
			)
		)
	)
	(symbol
		(lib_id "antmicroCapacitors0603:C_22u_16V_0603")
		(at 328.93 207.01 90)
		(unit 1)
		(exclude_from_sim no)
		(in_bom yes)
		(on_board yes)
		(dnp no)
		(property "Reference" "C128"
			(at 329.565 202.565 90)
			(effects
				(font
					(size 1.27 1.27)
				)
				(justify right)
			)
		)
		(property "Value" "C_22u_16V_0603"
			(at 339.09 186.69 0)
			(effects
				(font
					(size 1.27 1.27)
					(thickness 0.15)
				)
				(justify left bottom)
				(hide yes)
			)
		)
		(property "Footprint" "antmicro-footprints:C_0603_1608Metric_EIA"
			(at 341.63 186.69 0)
			(effects
				(font
					(size 1.27 1.27)
					(thickness 0.15)
				)
				(justify left bottom)
				(hide yes)
			)
		)
		(property "Datasheet" "https://product.samsungsem.com/mlcc/CL10A226MO7JZN.do"
			(at 344.17 186.69 0)
			(effects
				(font
					(size 1.27 1.27)
					(thickness 0.15)
				)
				(justify left bottom)
				(hide yes)
			)
		)
		(property "Description" "SMD Multilayer Ceramic Capacitor"
			(at 328.93 207.01 0)
			(effects
				(font
					(size 1.27 1.27)
				)
				(hide yes)
			)
		)
		(property "Manufacturer" "Samsung Electro-Mechanics"
			(at 349.25 186.69 0)
			(effects
				(font
					(size 1.27 1.27)
					(thickness 0.15)
				)
				(justify left bottom)
				(hide yes)
			)
		)
		(property "MPN" "CL10A226MO7JZNC"
			(at 346.71 186.69 0)
			(effects
				(font
					(size 1.27 1.27)
					(thickness 0.15)
				)
				(justify left bottom)
				(hide yes)
			)
		)
		(property "Val" "22u"
			(at 329.565 206.375 90)
			(effects
				(font
					(size 1.27 1.27)
					(thickness 0.15)
				)
				(justify right)
			)
		)
		(property "License" "Apache-2.0"
			(at 351.79 186.69 0)
			(effects
				(font
					(size 1.27 1.27)
					(thickness 0.15)
				)
				(justify left bottom)
				(hide yes)
			)
		)
		(property "Author" "Antmicro"
			(at 354.33 186.69 0)
			(effects
				(font
					(size 1.27 1.27)
					(thickness 0.15)
				)
				(justify left bottom)
				(hide yes)
			)
		)
		(property "Voltage" "16V"
			(at 356.87 186.69 0)
			(effects
				(font
					(size 1.27 1.27)
				)
				(justify left bottom)
				(hide yes)
			)
		)
		(property "Dielectric" ""
			(at 359.41 186.69 0)
			(effects
				(font
					(size 1.27 1.27)
				)
				(justify left bottom)
				(hide yes)
			)
		)
		(pin "1"
		)
		(pin "2"
		)
		(instances
			(project "jetson-orin-baseboard"
				(path ""
					(reference "C128")
					(unit 1)
				)
			)
		)
	)
	(symbol
		(lib_id "antmicroCapacitors0603:C_22u_16V_0603")
		(at 336.55 148.59 90)
		(unit 1)
		(exclude_from_sim no)
		(in_bom yes)
		(on_board yes)
		(dnp no)
		(property "Reference" "C153"
			(at 337.185 144.145 90)
			(effects
				(font
					(size 1.27 1.27)
				)
				(justify right)
			)
		)
		(property "Value" "C_22u_16V_0603"
			(at 346.71 128.27 0)
			(effects
				(font
					(size 1.27 1.27)
					(thickness 0.15)
				)
				(justify left bottom)
				(hide yes)
			)
		)
		(property "Footprint" "antmicro-footprints:C_0603_1608Metric_EIA"
			(at 349.25 128.27 0)
			(effects
				(font
					(size 1.27 1.27)
					(thickness 0.15)
				)
				(justify left bottom)
				(hide yes)
			)
		)
		(property "Datasheet" "https://product.samsungsem.com/mlcc/CL10A226MO7JZN.do"
			(at 351.79 128.27 0)
			(effects
				(font
					(size 1.27 1.27)
					(thickness 0.15)
				)
				(justify left bottom)
				(hide yes)
			)
		)
		(property "Description" "SMD Multilayer Ceramic Capacitor"
			(at 336.55 148.59 0)
			(effects
				(font
					(size 1.27 1.27)
				)
				(hide yes)
			)
		)
		(property "Manufacturer" "Samsung Electro-Mechanics"
			(at 356.87 128.27 0)
			(effects
				(font
					(size 1.27 1.27)
					(thickness 0.15)
				)
				(justify left bottom)
				(hide yes)
			)
		)
		(property "MPN" "CL10A226MO7JZNC"
			(at 354.33 128.27 0)
			(effects
				(font
					(size 1.27 1.27)
					(thickness 0.15)
				)
				(justify left bottom)
				(hide yes)
			)
		)
		(property "Val" "22u"
			(at 337.185 147.955 90)
			(effects
				(font
					(size 1.27 1.27)
					(thickness 0.15)
				)
				(justify right)
			)
		)
		(property "License" "Apache-2.0"
			(at 359.41 128.27 0)
			(effects
				(font
					(size 1.27 1.27)
					(thickness 0.15)
				)
				(justify left bottom)
				(hide yes)
			)
		)
		(property "Author" "Antmicro"
			(at 361.95 128.27 0)
			(effects
				(font
					(size 1.27 1.27)
					(thickness 0.15)
				)
				(justify left bottom)
				(hide yes)
			)
		)
		(property "Voltage" "16V"
			(at 364.49 128.27 0)
			(effects
				(font
					(size 1.27 1.27)
				)
				(justify left bottom)
				(hide yes)
			)
		)
		(property "Dielectric" ""
			(at 367.03 128.27 0)
			(effects
				(font
					(size 1.27 1.27)
				)
				(justify left bottom)
				(hide yes)
			)
		)
		(pin "1"
		)
		(pin "2"
		)
		(instances
			(project "jetson-orin-baseboard"
				(path ""
					(reference "C153")
					(unit 1)
				)
			)
		)
	)
	(symbol
		(lib_id "antmicropower:GND")
		(at 43.18 46.99 0)
		(unit 1)
		(exclude_from_sim no)
		(in_bom yes)
		(on_board yes)
		(dnp no)
		(property "Reference" "#PWR0337"
			(at 43.18 53.34 0)
			(effects
				(font
					(size 1.27 1.27)
				)
				(justify left bottom)
				(hide yes)
			)
		)
		(property "Value" "GND"
			(at 43.18 50.8 0)
			(effects
				(font
					(size 1.27 1.27)
					(thickness 0.15)
				)
			)
		)
		(property "Footprint" ""
			(at 52.07 54.61 0)
			(effects
				(font
					(size 1.27 1.27)
					(thickness 0.15)
				)
				(justify left bottom)
				(hide yes)
			)
		)
		(property "Datasheet" ""
			(at 52.07 59.69 0)
			(effects
				(font
					(size 1.27 1.27)
					(thickness 0.15)
				)
				(justify left bottom)
				(hide yes)
			)
		)
		(property "Description" ""
			(at 43.18 46.99 0)
			(effects
				(font
					(size 1.27 1.27)
				)
				(hide yes)
			)
		)
		(property "Author" "Antmicro"
			(at 52.07 54.61 0)
			(effects
				(font
					(size 1.27 1.27)
					(thickness 0.15)
				)
				(justify left bottom)
				(hide yes)
			)
		)
		(property "License" "Apache-2.0"
			(at 52.07 57.15 0)
			(effects
				(font
					(size 1.27 1.27)
					(thickness 0.15)
				)
				(justify left bottom)
				(hide yes)
			)
		)
		(pin "1"
		)
		(instances
			(project "jetson-orin-baseboard"
				(path ""
					(reference "#PWR0337")
					(unit 1)
				)
			)
		)
	)
	(symbol
		(lib_id "antmicroTransistorsBipolarArrays:BCM857BS-7-F")
		(at 69.85 137.16 180)
		(unit 1)
		(exclude_from_sim no)
		(in_bom yes)
		(on_board yes)
		(dnp no)
		(property "Reference" "Q13"
			(at 53.975 132.08 0)
			(effects
				(font
					(size 1.27 1.27)
				)
				(justify left top)
			)
		)
		(property "Value" "BCM857BS-7-F"
			(at 46.99 134.62 0)
			(effects
				(font
					(size 1.27 1.27)
					(thickness 0.15)
				)
				(justify left bottom)
				(hide yes)
			)
		)
		(property "Footprint" "antmicro-footprints:SOT-363"
			(at 46.99 132.08 0)
			(effects
				(font
					(size 1.27 1.27)
					(thickness 0.15)
				)
				(justify left bottom)
				(hide yes)
			)
		)
		(property "Datasheet" "https://www.diodes.com/assets/Datasheets/BCM857BS.pdf"
			(at 46.99 129.54 0)
			(effects
				(font
					(size 1.27 1.27)
					(thickness 0.15)
				)
				(justify left bottom)
				(hide yes)
			)
		)
		(property "Description" ""
			(at 69.85 137.16 0)
			(effects
				(font
					(size 1.27 1.27)
				)
				(hide yes)
			)
		)
		(property "MPN" "BCM857BS-7-F"
			(at 53.975 134.62 0)
			(effects
				(font
					(size 1.27 1.27)
					(thickness 0.15)
				)
				(justify left top)
			)
		)
		(property "Manufacturer" "Diodes Incorporated"
			(at 46.99 124.46 0)
			(effects
				(font
					(size 1.27 1.27)
					(thickness 0.15)
				)
				(justify left bottom)
				(hide yes)
			)
		)
		(property "Author" "Antmicro"
			(at 46.99 121.92 0)
			(effects
				(font
					(size 1.27 1.27)
					(thickness 0.15)
				)
				(justify left bottom)
				(hide yes)
			)
		)
		(property "License" "Apache-2.0"
			(at 46.99 119.38 0)
			(effects
				(font
					(size 1.27 1.27)
					(thickness 0.15)
				)
				(justify left bottom)
				(hide yes)
			)
		)
		(pin "1"
		)
		(pin "2"
		)
		(pin "3"
		)
		(pin "4"
		)
		(pin "5"
		)
		(pin "6"
		)
		(instances
			(project "jetson-orin-baseboard"
				(path ""
					(reference "Q13")
					(unit 1)
				)
			)
		)
	)
	(symbol
		(lib_id "antmicroTransistorsBipolarArrays:BCM857BS-7-F")
		(at 69.85 184.15 180)
		(unit 1)
		(exclude_from_sim no)
		(in_bom yes)
		(on_board yes)
		(dnp no)
		(property "Reference" "Q14"
			(at 53.975 179.07 0)
			(effects
				(font
					(size 1.27 1.27)
				)
				(justify left top)
			)
		)
		(property "Value" "BCM857BS-7-F"
			(at 46.99 181.61 0)
			(effects
				(font
					(size 1.27 1.27)
					(thickness 0.15)
				)
				(justify left bottom)
				(hide yes)
			)
		)
		(property "Footprint" "antmicro-footprints:SOT-363"
			(at 46.99 179.07 0)
			(effects
				(font
					(size 1.27 1.27)
					(thickness 0.15)
				)
				(justify left bottom)
				(hide yes)
			)
		)
		(property "Datasheet" "https://www.diodes.com/assets/Datasheets/BCM857BS.pdf"
			(at 46.99 176.53 0)
			(effects
				(font
					(size 1.27 1.27)
					(thickness 0.15)
				)
				(justify left bottom)
				(hide yes)
			)
		)
		(property "Description" ""
			(at 69.85 184.15 0)
			(effects
				(font
					(size 1.27 1.27)
				)
				(hide yes)
			)
		)
		(property "MPN" "BCM857BS-7-F"
			(at 53.975 181.61 0)
			(effects
				(font
					(size 1.27 1.27)
					(thickness 0.15)
				)
				(justify left top)
			)
		)
		(property "Manufacturer" "Diodes Incorporated"
			(at 46.99 171.45 0)
			(effects
				(font
					(size 1.27 1.27)
					(thickness 0.15)
				)
				(justify left bottom)
				(hide yes)
			)
		)
		(property "Author" "Antmicro"
			(at 46.99 168.91 0)
			(effects
				(font
					(size 1.27 1.27)
					(thickness 0.15)
				)
				(justify left bottom)
				(hide yes)
			)
		)
		(property "License" "Apache-2.0"
			(at 46.99 166.37 0)
			(effects
				(font
					(size 1.27 1.27)
					(thickness 0.15)
				)
				(justify left bottom)
				(hide yes)
			)
		)
		(pin "1"
		)
		(pin "2"
		)
		(pin "3"
		)
		(pin "4"
		)
		(pin "5"
		)
		(pin "6"
		)
		(instances
			(project "jetson-orin-baseboard"
				(path ""
					(reference "Q14")
					(unit 1)
				)
			)
		)
	)
	(symbol
		(lib_id "antmicropower:GND")
		(at 313.69 213.36 0)
		(unit 1)
		(exclude_from_sim no)
		(in_bom yes)
		(on_board yes)
		(dnp no)
		(property "Reference" "#PWR0339"
			(at 313.69 219.71 0)
			(effects
				(font
					(size 1.27 1.27)
				)
				(justify left bottom)
				(hide yes)
			)
		)
		(property "Value" "GND"
			(at 313.69 217.17 0)
			(effects
				(font
					(size 1.27 1.27)
					(thickness 0.15)
				)
			)
		)
		(property "Footprint" ""
			(at 322.58 220.98 0)
			(effects
				(font
					(size 1.27 1.27)
					(thickness 0.15)
				)
				(justify left bottom)
				(hide yes)
			)
		)
		(property "Datasheet" ""
			(at 322.58 226.06 0)
			(effects
				(font
					(size 1.27 1.27)
					(thickness 0.15)
				)
				(justify left bottom)
				(hide yes)
			)
		)
		(property "Description" ""
			(at 313.69 213.36 0)
			(effects
				(font
					(size 1.27 1.27)
				)
				(hide yes)
			)
		)
		(property "Author" "Antmicro"
			(at 322.58 220.98 0)
			(effects
				(font
					(size 1.27 1.27)
					(thickness 0.15)
				)
				(justify left bottom)
				(hide yes)
			)
		)
		(property "License" "Apache-2.0"
			(at 322.58 223.52 0)
			(effects
				(font
					(size 1.27 1.27)
					(thickness 0.15)
				)
				(justify left bottom)
				(hide yes)
			)
		)
		(pin "1"
		)
		(instances
			(project "jetson-orin-baseboard"
				(path ""
					(reference "#PWR0339")
					(unit 1)
				)
			)
		)
	)
	(symbol
		(lib_id "antmicropower:VCC")
		(at 189.23 128.27 0)
		(unit 1)
		(exclude_from_sim no)
		(in_bom yes)
		(on_board yes)
		(dnp no)
		(property "Reference" "#PWR0248"
			(at 189.23 132.08 0)
			(effects
				(font
					(size 1.27 1.27)
				)
				(justify left bottom)
				(hide yes)
			)
		)
		(property "Value" "VCC"
			(at 187.325 124.46 0)
			(effects
				(font
					(size 1.27 1.27)
				)
				(justify left)
			)
		)
		(property "Footprint" ""
			(at 189.23 128.27 0)
			(effects
				(font
					(size 1.27 1.27)
				)
				(hide yes)
			)
		)
		(property "Datasheet" ""
			(at 189.23 128.27 0)
			(effects
				(font
					(size 1.27 1.27)
				)
				(hide yes)
			)
		)
		(property "Description" ""
			(at 189.23 128.27 0)
			(effects
				(font
					(size 1.27 1.27)
				)
				(hide yes)
			)
		)
		(pin "1"
		)
		(instances
			(project "jetson-orin-baseboard"
				(path ""
					(reference "#PWR0248")
					(unit 1)
				)
			)
		)
	)
	(symbol
		(lib_id "antmicroCapacitors0603:C_22u_16V_0603")
		(at 328.93 148.59 90)
		(unit 1)
		(exclude_from_sim no)
		(in_bom yes)
		(on_board yes)
		(dnp no)
		(property "Reference" "C129"
			(at 329.565 144.145 90)
			(effects
				(font
					(size 1.27 1.27)
				)
				(justify right)
			)
		)
		(property "Value" "C_22u_16V_0603"
			(at 339.09 128.27 0)
			(effects
				(font
					(size 1.27 1.27)
					(thickness 0.15)
				)
				(justify left bottom)
				(hide yes)
			)
		)
		(property "Footprint" "antmicro-footprints:C_0603_1608Metric_EIA"
			(at 341.63 128.27 0)
			(effects
				(font
					(size 1.27 1.27)
					(thickness 0.15)
				)
				(justify left bottom)
				(hide yes)
			)
		)
		(property "Datasheet" "https://product.samsungsem.com/mlcc/CL10A226MO7JZN.do"
			(at 344.17 128.27 0)
			(effects
				(font
					(size 1.27 1.27)
					(thickness 0.15)
				)
				(justify left bottom)
				(hide yes)
			)
		)
		(property "Description" "SMD Multilayer Ceramic Capacitor"
			(at 328.93 148.59 0)
			(effects
				(font
					(size 1.27 1.27)
				)
				(hide yes)
			)
		)
		(property "Manufacturer" "Samsung Electro-Mechanics"
			(at 349.25 128.27 0)
			(effects
				(font
					(size 1.27 1.27)
					(thickness 0.15)
				)
				(justify left bottom)
				(hide yes)
			)
		)
		(property "MPN" "CL10A226MO7JZNC"
			(at 346.71 128.27 0)
			(effects
				(font
					(size 1.27 1.27)
					(thickness 0.15)
				)
				(justify left bottom)
				(hide yes)
			)
		)
		(property "Val" "22u"
			(at 329.565 147.955 90)
			(effects
				(font
					(size 1.27 1.27)
					(thickness 0.15)
				)
				(justify right)
			)
		)
		(property "License" "Apache-2.0"
			(at 351.79 128.27 0)
			(effects
				(font
					(size 1.27 1.27)
					(thickness 0.15)
				)
				(justify left bottom)
				(hide yes)
			)
		)
		(property "Author" "Antmicro"
			(at 354.33 128.27 0)
			(effects
				(font
					(size 1.27 1.27)
					(thickness 0.15)
				)
				(justify left bottom)
				(hide yes)
			)
		)
		(property "Voltage" "16V"
			(at 356.87 128.27 0)
			(effects
				(font
					(size 1.27 1.27)
				)
				(justify left bottom)
				(hide yes)
			)
		)
		(property "Dielectric" ""
			(at 359.41 128.27 0)
			(effects
				(font
					(size 1.27 1.27)
				)
				(justify left bottom)
				(hide yes)
			)
		)
		(pin "1"
		)
		(pin "2"
		)
		(instances
			(project "jetson-orin-baseboard"
				(path ""
					(reference "C129")
					(unit 1)
				)
			)
		)
	)
	(symbol
		(lib_id "antmicropower:GND")
		(at 198.12 154.94 0)
		(unit 1)
		(exclude_from_sim no)
		(in_bom yes)
		(on_board yes)
		(dnp no)
		(property "Reference" "#PWR0215"
			(at 198.12 161.29 0)
			(effects
				(font
					(size 1.27 1.27)
				)
				(justify left bottom)
				(hide yes)
			)
		)
		(property "Value" "GND"
			(at 198.12 158.75 0)
			(effects
				(font
					(size 1.27 1.27)
					(thickness 0.15)
				)
			)
		)
		(property "Footprint" ""
			(at 207.01 162.56 0)
			(effects
				(font
					(size 1.27 1.27)
					(thickness 0.15)
				)
				(justify left bottom)
				(hide yes)
			)
		)
		(property "Datasheet" ""
			(at 207.01 167.64 0)
			(effects
				(font
					(size 1.27 1.27)
					(thickness 0.15)
				)
				(justify left bottom)
				(hide yes)
			)
		)
		(property "Description" ""
			(at 198.12 154.94 0)
			(effects
				(font
					(size 1.27 1.27)
				)
				(hide yes)
			)
		)
		(property "Author" "Antmicro"
			(at 207.01 162.56 0)
			(effects
				(font
					(size 1.27 1.27)
					(thickness 0.15)
				)
				(justify left bottom)
				(hide yes)
			)
		)
		(property "License" "Apache-2.0"
			(at 207.01 165.1 0)
			(effects
				(font
					(size 1.27 1.27)
					(thickness 0.15)
				)
				(justify left bottom)
				(hide yes)
			)
		)
		(pin "1"
		)
		(instances
			(project "jetson-orin-baseboard"
				(path ""
					(reference "#PWR0215")
					(unit 1)
				)
			)
		)
	)
	(symbol
		(lib_name "TP_0.75mm_SMD_3")
		(lib_id "antmicroTestPoints:TP_0.75mm_SMD")
		(at 267.97 36.83 90)
		(unit 1)
		(exclude_from_sim no)
		(in_bom no)
		(on_board yes)
		(dnp no)
		(property "Reference" "TP33"
			(at 267.97 33.02 0)
			(effects
				(font
					(size 1.27 1.27)
				)
				(justify left)
			)
		)
		(property "Value" "TP_0.75mm_SMD"
			(at 271.78 26.67 0)
			(effects
				(font
					(size 1.27 1.27)
					(thickness 0.15)
				)
				(justify left bottom)
				(hide yes)
			)
		)
		(property "Footprint" "antmicro-footprints:TP_SMD_0.75mm"
			(at 274.32 26.67 0)
			(effects
				(font
					(size 1.27 1.27)
					(thickness 0.15)
				)
				(justify left bottom)
				(hide yes)
			)
		)
		(property "Datasheet" ""
			(at 280.67 19.05 0)
			(effects
				(font
					(size 1.27 1.27)
					(thickness 0.15)
				)
				(justify left bottom)
				(hide yes)
			)
		)
		(property "Description" ""
			(at 267.97 36.83 0)
			(effects
				(font
					(size 1.27 1.27)
				)
				(hide yes)
			)
		)
		(property "MPN" ""
			(at 279.4 26.035 0)
			(effects
				(font
					(size 1.27 1.27)
					(thickness 0.15)
				)
				(justify left bottom)
				(hide yes)
			)
		)
		(property "Manufacturer" ""
			(at 274.32 26.035 0)
			(effects
				(font
					(size 1.27 1.27)
					(thickness 0.15)
				)
				(justify left bottom)
				(hide yes)
			)
		)
		(property "Author" "Antmicro"
			(at 276.86 26.67 0)
			(effects
				(font
					(size 1.27 1.27)
					(thickness 0.15)
				)
				(justify left bottom)
				(hide yes)
			)
		)
		(property "License" "Apache-2.0"
			(at 279.4 26.67 0)
			(effects
				(font
					(size 1.27 1.27)
					(thickness 0.15)
				)
				(justify left bottom)
				(hide yes)
			)
		)
		(pin "1"
		)
		(instances
			(project "jetson-orin-baseboard"
				(path ""
					(reference "TP33")
					(unit 1)
				)
			)
		)
	)
	(symbol
		(lib_id "antmicroTestPoints:TP_0.75mm_SMD")
		(at 388.62 134.62 0)
		(unit 1)
		(exclude_from_sim no)
		(in_bom no)
		(on_board yes)
		(dnp no)
		(property "Reference" "TP53"
			(at 392.43 134.62 0)
			(effects
				(font
					(size 1.27 1.27)
				)
				(justify left)
			)
		)
		(property "Value" "TP_0.75mm_SMD"
			(at 398.78 138.43 0)
			(effects
				(font
					(size 1.27 1.27)
					(thickness 0.15)
				)
				(justify left bottom)
				(hide yes)
			)
		)
		(property "Footprint" "antmicro-footprints:TP_SMD_0.75mm"
			(at 398.78 140.97 0)
			(effects
				(font
					(size 1.27 1.27)
					(thickness 0.15)
				)
				(justify left bottom)
				(hide yes)
			)
		)
		(property "Datasheet" ""
			(at 406.4 147.32 0)
			(effects
				(font
					(size 1.27 1.27)
					(thickness 0.15)
				)
				(justify left bottom)
				(hide yes)
			)
		)
		(property "Description" ""
			(at 388.62 134.62 0)
			(effects
				(font
					(size 1.27 1.27)
				)
				(hide yes)
			)
		)
		(property "MPN" ""
			(at 399.415 146.05 0)
			(effects
				(font
					(size 1.27 1.27)
					(thickness 0.15)
				)
				(justify left bottom)
				(hide yes)
			)
		)
		(property "Manufacturer" ""
			(at 399.415 140.97 0)
			(effects
				(font
					(size 1.27 1.27)
					(thickness 0.15)
				)
				(justify left bottom)
				(hide yes)
			)
		)
		(property "Author" "Antmicro"
			(at 398.78 143.51 0)
			(effects
				(font
					(size 1.27 1.27)
					(thickness 0.15)
				)
				(justify left bottom)
				(hide yes)
			)
		)
		(property "License" "Apache-2.0"
			(at 398.78 146.05 0)
			(effects
				(font
					(size 1.27 1.27)
					(thickness 0.15)
				)
				(justify left bottom)
				(hide yes)
			)
		)
		(pin "1"
		)
		(instances
			(project "jetson-orin-baseboard"
				(path ""
					(reference "TP53")
					(unit 1)
				)
			)
		)
	)
	(symbol
		(lib_id "antmicropower:GND")
		(at 50.8 200.66 0)
		(unit 1)
		(exclude_from_sim no)
		(in_bom yes)
		(on_board yes)
		(dnp no)
		(property "Reference" "#PWR0290"
			(at 50.8 207.01 0)
			(effects
				(font
					(size 1.27 1.27)
				)
				(justify left bottom)
				(hide yes)
			)
		)
		(property "Value" "GND"
			(at 50.8 204.47 0)
			(effects
				(font
					(size 1.27 1.27)
					(thickness 0.15)
				)
			)
		)
		(property "Footprint" ""
			(at 59.69 208.28 0)
			(effects
				(font
					(size 1.27 1.27)
					(thickness 0.15)
				)
				(justify left bottom)
				(hide yes)
			)
		)
		(property "Datasheet" ""
			(at 59.69 213.36 0)
			(effects
				(font
					(size 1.27 1.27)
					(thickness 0.15)
				)
				(justify left bottom)
				(hide yes)
			)
		)
		(property "Description" ""
			(at 50.8 200.66 0)
			(effects
				(font
					(size 1.27 1.27)
				)
				(hide yes)
			)
		)
		(property "Author" "Antmicro"
			(at 59.69 208.28 0)
			(effects
				(font
					(size 1.27 1.27)
					(thickness 0.15)
				)
				(justify left bottom)
				(hide yes)
			)
		)
		(property "License" "Apache-2.0"
			(at 59.69 210.82 0)
			(effects
				(font
					(size 1.27 1.27)
					(thickness 0.15)
				)
				(justify left bottom)
				(hide yes)
			)
		)
		(pin "1"
		)
		(instances
			(project "jetson-orin-baseboard"
				(path ""
					(reference "#PWR0290")
					(unit 1)
				)
			)
		)
	)
	(symbol
		(lib_id "antmicroCapacitors0402:C_1u_25V_0402")
		(at 119.38 171.45 90)
		(unit 1)
		(exclude_from_sim no)
		(in_bom yes)
		(on_board yes)
		(dnp no)
		(property "Reference" "C150"
			(at 121.285 167.64 90)
			(effects
				(font
					(size 1.27 1.27)
				)
				(justify right)
			)
		)
		(property "Value" "C_1u_25V_0402"
			(at 129.54 151.13 0)
			(effects
				(font
					(size 1.27 1.27)
					(thickness 0.15)
				)
				(justify left bottom)
				(hide yes)
			)
		)
		(property "Footprint" "antmicro-footprints:C_0402_1005Metric"
			(at 132.08 151.13 0)
			(effects
				(font
					(size 1.27 1.27)
					(thickness 0.15)
				)
				(justify left bottom)
				(hide yes)
			)
		)
		(property "Datasheet" "https://www.murata.com/products/productdetail?partno=GRM155R61E105KE11%23"
			(at 134.62 151.13 0)
			(effects
				(font
					(size 1.27 1.27)
					(thickness 0.15)
				)
				(justify left bottom)
				(hide yes)
			)
		)
		(property "Description" ""
			(at 119.38 171.45 0)
			(effects
				(font
					(size 1.27 1.27)
				)
				(hide yes)
			)
		)
		(property "Manufacturer" "Murata"
			(at 139.7 151.13 0)
			(effects
				(font
					(size 1.27 1.27)
					(thickness 0.15)
				)
				(justify left bottom)
				(hide yes)
			)
		)
		(property "MPN" "GRM155R61E105KE11J"
			(at 137.16 151.13 0)
			(effects
				(font
					(size 1.27 1.27)
					(thickness 0.15)
				)
				(justify left bottom)
				(hide yes)
			)
		)
		(property "Val" "1u"
			(at 121.285 170.18 90)
			(effects
				(font
					(size 1.27 1.27)
					(thickness 0.15)
				)
				(justify right)
			)
		)
		(property "License" "Apache-2.0"
			(at 142.24 151.13 0)
			(effects
				(font
					(size 1.27 1.27)
					(thickness 0.15)
				)
				(justify left bottom)
				(hide yes)
			)
		)
		(property "Author" "Antmicro"
			(at 144.78 151.13 0)
			(effects
				(font
					(size 1.27 1.27)
					(thickness 0.15)
				)
				(justify left bottom)
				(hide yes)
			)
		)
		(property "Voltage" "25V"
			(at 147.32 151.13 0)
			(effects
				(font
					(size 1.27 1.27)
				)
				(justify left bottom)
				(hide yes)
			)
		)
		(property "Dielectric" "X5R"
			(at 149.86 151.13 0)
			(effects
				(font
					(size 1.27 1.27)
				)
				(justify left bottom)
				(hide yes)
			)
		)
		(pin "1"
		)
		(pin "2"
		)
		(instances
			(project "jetson-orin-baseboard"
				(path ""
					(reference "C150")
					(unit 1)
				)
			)
		)
	)
	(symbol
		(lib_name "SIC431AED-T1-GE3_1")
		(lib_id "antmicroDCDCConverters:SIC431AED-T1-GE3")
		(at 251.46 129.54 0)
		(unit 1)
		(exclude_from_sim no)
		(in_bom yes)
		(on_board yes)
		(dnp no)
		(property "Reference" "U1"
			(at 261.62 123.19 0)
			(effects
				(font
					(size 1.27 1.27)
					(thickness 0.15)
				)
			)
		)
		(property "Value" "SIC431AED-T1-GE3"
			(at 284.48 137.16 0)
			(effects
				(font
					(size 1.27 1.27)
					(thickness 0.15)
				)
				(justify left bottom)
				(hide yes)
			)
		)
		(property "Footprint" "antmicro-footprints:MLP44-24L_4x4x0.75mm"
			(at 284.48 139.7 0)
			(effects
				(font
					(size 1.27 1.27)
					(thickness 0.15)
				)
				(justify left bottom)
				(hide yes)
			)
		)
		(property "Datasheet" "https://www.vishay.com/docs/74589/sic431.pdf"
			(at 284.48 142.24 0)
			(effects
				(font
					(size 1.27 1.27)
					(thickness 0.15)
				)
				(justify left bottom)
				(hide yes)
			)
		)
		(property "Description" ""
			(at 251.46 129.54 0)
			(effects
				(font
					(size 1.27 1.27)
				)
				(hide yes)
			)
		)
		(property "Manufacturer" "Vishay"
			(at 284.48 144.78 0)
			(effects
				(font
					(size 1.27 1.27)
					(thickness 0.15)
				)
				(justify left bottom)
				(hide yes)
			)
		)
		(property "MPN" "SIC431AED-T1-GE3 "
			(at 262.89 125.73 0)
			(effects
				(font
					(size 1.27 1.27)
					(thickness 0.15)
				)
			)
		)
		(property "Author" "Antmicro"
			(at 284.48 147.32 0)
			(effects
				(font
					(size 1.27 1.27)
					(thickness 0.15)
				)
				(justify left bottom)
				(hide yes)
			)
		)
		(property "License" "Apache-2.0"
			(at 284.48 149.86 0)
			(effects
				(font
					(size 1.27 1.27)
					(thickness 0.15)
				)
				(justify left bottom)
				(hide yes)
			)
		)
		(pin "7"
		)
		(pin "16"
		)
		(pin "18"
		)
		(pin "8"
		)
		(pin "15"
		)
		(pin "14"
		)
		(pin "20"
		)
		(pin "2"
		)
		(pin "12"
		)
		(pin "22"
		)
		(pin "11"
		)
		(pin "26"
		)
		(pin "10"
		)
		(pin "19"
		)
		(pin "5"
		)
		(pin "4"
		)
		(pin "17"
		)
		(pin "6"
		)
		(pin "3"
		)
		(pin "1"
		)
		(pin "13"
		)
		(pin "23"
		)
		(pin "25"
		)
		(pin "21"
		)
		(pin "24"
		)
		(pin "9"
		)
		(pin "27"
		)
		(pin "28"
		)
		(instances
			(project "jetson-orin-baseboard"
				(path ""
					(reference "U1")
					(unit 1)
				)
			)
		)
	)
	(symbol
		(lib_id "antmicropower:GND")
		(at 172.72 181.61 0)
		(unit 1)
		(exclude_from_sim no)
		(in_bom yes)
		(on_board yes)
		(dnp no)
		(property "Reference" "#PWR0178"
			(at 172.72 187.96 0)
			(effects
				(font
					(size 1.27 1.27)
				)
				(justify left bottom)
				(hide yes)
			)
		)
		(property "Value" "GND"
			(at 172.72 185.42 0)
			(effects
				(font
					(size 1.27 1.27)
					(thickness 0.15)
				)
			)
		)
		(property "Footprint" ""
			(at 181.61 189.23 0)
			(effects
				(font
					(size 1.27 1.27)
					(thickness 0.15)
				)
				(justify left bottom)
				(hide yes)
			)
		)
		(property "Datasheet" ""
			(at 181.61 194.31 0)
			(effects
				(font
					(size 1.27 1.27)
					(thickness 0.15)
				)
				(justify left bottom)
				(hide yes)
			)
		)
		(property "Description" ""
			(at 172.72 181.61 0)
			(effects
				(font
					(size 1.27 1.27)
				)
				(hide yes)
			)
		)
		(property "Author" "Antmicro"
			(at 181.61 189.23 0)
			(effects
				(font
					(size 1.27 1.27)
					(thickness 0.15)
				)
				(justify left bottom)
				(hide yes)
			)
		)
		(property "License" "Apache-2.0"
			(at 181.61 191.77 0)
			(effects
				(font
					(size 1.27 1.27)
					(thickness 0.15)
				)
				(justify left bottom)
				(hide yes)
			)
		)
		(pin "1"
		)
		(instances
			(project "jetson-orin-baseboard"
				(path ""
					(reference "#PWR0178")
					(unit 1)
				)
			)
		)
	)
	(symbol
		(lib_id "antmicroResistors0402:R_2k7_0402")
		(at 223.52 119.38 90)
		(unit 1)
		(exclude_from_sim no)
		(in_bom yes)
		(on_board yes)
		(dnp no)
		(fields_autoplaced yes)
		(property "Reference" "R169"
			(at 226.06 115.57 90)
			(effects
				(font
					(size 1.27 1.27)
					(thickness 0.15)
				)
				(justify right)
			)
		)
		(property "Value" "R_2k7_0402"
			(at 236.22 99.06 0)
			(effects
				(font
					(size 1.27 1.27)
					(thickness 0.15)
				)
				(justify left bottom)
				(hide yes)
			)
		)
		(property "Footprint" "antmicro-footprints:R_0402_1005Metric"
			(at 238.76 99.06 0)
			(effects
				(font
					(size 1.27 1.27)
					(thickness 0.15)
				)
				(justify left bottom)
				(hide yes)
			)
		)
		(property "Datasheet" "https://www.bourns.com/docs/product-datasheets/cr.pdf"
			(at 241.3 99.06 0)
			(effects
				(font
					(size 1.27 1.27)
					(thickness 0.15)
				)
				(justify left bottom)
				(hide yes)
			)
		)
		(property "Description" "SMD Chip Resistor, 2.7 kohm, ± 1%, 63 mW, 0402 [1005 Metric], Thick Film, General Purpose"
			(at 223.52 119.38 0)
			(effects
				(font
					(size 1.27 1.27)
				)
				(hide yes)
			)
		)
		(property "MPN" "CR0402-FX-2701GLF"
			(at 243.84 99.06 0)
			(effects
				(font
					(size 1.27 1.27)
					(thickness 0.15)
				)
				(justify left bottom)
				(hide yes)
			)
		)
		(property "Manufacturer" "Bourns"
			(at 246.38 99.06 0)
			(effects
				(font
					(size 1.27 1.27)
					(thickness 0.15)
				)
				(justify left bottom)
				(hide yes)
			)
		)
		(property "License" "Apache-2.0"
			(at 248.92 99.06 0)
			(effects
				(font
					(size 1.27 1.27)
					(thickness 0.15)
				)
				(justify left bottom)
				(hide yes)
			)
		)
		(property "Author" "Antmicro"
			(at 251.46 99.06 0)
			(effects
				(font
					(size 1.27 1.27)
					(thickness 0.15)
				)
				(justify left bottom)
				(hide yes)
			)
		)
		(property "Val" "2k7"
			(at 226.06 118.11 90)
			(effects
				(font
					(size 1.27 1.27)
					(thickness 0.15)
				)
				(justify right)
			)
		)
		(property "Tolerance" "1%"
			(at 233.68 99.06 0)
			(effects
				(font
					(size 1.27 1.27)
				)
				(justify left bottom)
				(hide yes)
			)
		)
		(pin "2"
		)
		(pin "1"
		)
		(instances
			(project ""
				(path ""
					(reference "R169")
					(unit 1)
				)
			)
		)
	)
	(symbol
		(lib_id "antmicropower:GND")
		(at 151.13 69.85 0)
		(unit 1)
		(exclude_from_sim no)
		(in_bom yes)
		(on_board yes)
		(dnp no)
		(property "Reference" "#PWR0263"
			(at 151.13 76.2 0)
			(effects
				(font
					(size 1.27 1.27)
				)
				(justify left bottom)
				(hide yes)
			)
		)
		(property "Value" "GND"
			(at 151.13 73.66 0)
			(effects
				(font
					(size 1.27 1.27)
					(thickness 0.15)
				)
			)
		)
		(property "Footprint" ""
			(at 160.02 77.47 0)
			(effects
				(font
					(size 1.27 1.27)
					(thickness 0.15)
				)
				(justify left bottom)
				(hide yes)
			)
		)
		(property "Datasheet" ""
			(at 160.02 82.55 0)
			(effects
				(font
					(size 1.27 1.27)
					(thickness 0.15)
				)
				(justify left bottom)
				(hide yes)
			)
		)
		(property "Description" ""
			(at 151.13 69.85 0)
			(effects
				(font
					(size 1.27 1.27)
				)
				(hide yes)
			)
		)
		(property "Author" "Antmicro"
			(at 160.02 77.47 0)
			(effects
				(font
					(size 1.27 1.27)
					(thickness 0.15)
				)
				(justify left bottom)
				(hide yes)
			)
		)
		(property "License" "Apache-2.0"
			(at 160.02 80.01 0)
			(effects
				(font
					(size 1.27 1.27)
					(thickness 0.15)
				)
				(justify left bottom)
				(hide yes)
			)
		)
		(pin "1"
		)
		(instances
			(project "jetson-orin-baseboard"
				(path ""
					(reference "#PWR0263")
					(unit 1)
				)
			)
		)
	)
	(symbol
		(lib_id "antmicroTransistorsFETsMOSFETsSingle:SSM3J332R")
		(at 132.08 172.72 270)
		(mirror x)
		(unit 1)
		(exclude_from_sim no)
		(in_bom yes)
		(on_board yes)
		(dnp no)
		(fields_autoplaced yes)
		(property "Reference" "Q18"
			(at 134.62 158.75 90)
			(effects
				(font
					(size 1.27 1.27)
				)
			)
		)
		(property "Value" "SSM3J332R"
			(at 129.54 158.75 0)
			(effects
				(font
					(size 1.27 1.27)
					(thickness 0.15)
				)
				(justify left bottom)
				(hide yes)
			)
		)
		(property "Footprint" "antmicro-footprints:SOT-23-3"
			(at 127 158.75 0)
			(effects
				(font
					(size 1.27 1.27)
					(thickness 0.15)
				)
				(justify left bottom)
				(hide yes)
			)
		)
		(property "Datasheet" "https://www.mouser.com/datasheet/2/408/SSM3J332R_datasheet_en_20181015-1150575.pdf"
			(at 124.46 158.75 0)
			(effects
				(font
					(size 1.27 1.27)
					(thickness 0.15)
				)
				(justify left bottom)
				(hide yes)
			)
		)
		(property "Description" ""
			(at 132.08 172.72 0)
			(effects
				(font
					(size 1.27 1.27)
				)
				(hide yes)
			)
		)
		(property "MPN" "SSM3J332R,LF"
			(at 134.62 161.29 90)
			(effects
				(font
					(size 1.27 1.27)
					(thickness 0.15)
				)
			)
		)
		(property "Manufacturer" "Toshiba"
			(at 119.38 158.75 0)
			(effects
				(font
					(size 1.27 1.27)
					(thickness 0.15)
				)
				(justify left bottom)
				(hide yes)
			)
		)
		(property "Author" "Antmicro"
			(at 116.84 158.75 0)
			(effects
				(font
					(size 1.27 1.27)
					(thickness 0.15)
				)
				(justify left bottom)
				(hide yes)
			)
		)
		(property "License" "Apache-2.0"
			(at 114.3 158.75 0)
			(effects
				(font
					(size 1.27 1.27)
					(thickness 0.15)
				)
				(justify left bottom)
				(hide yes)
			)
		)
		(pin "1"
		)
		(pin "2"
		)
		(pin "3"
		)
		(instances
			(project "jetson-orin-baseboard"
				(path ""
					(reference "Q18")
					(unit 1)
				)
			)
		)
	)
	(symbol
		(lib_id "antmicroFixedInductors:L_560n_17.7A_Bourns-SRP5030CA")
		(at 293.37 193.04 0)
		(unit 1)
		(exclude_from_sim no)
		(in_bom yes)
		(on_board yes)
		(dnp no)
		(fields_autoplaced yes)
		(property "Reference" "L1"
			(at 295.91 187.96 0)
			(effects
				(font
					(size 1.27 1.27)
					(thickness 0.15)
				)
			)
		)
		(property "Value" "L_560n_17.7A_Bourns-SRP5030CA"
			(at 307.34 195.58 0)
			(effects
				(font
					(size 1.27 1.27)
					(thickness 0.15)
				)
				(justify left bottom)
				(hide yes)
			)
		)
		(property "Footprint" "antmicro-footprints:L_Bourns-SRP5030CA"
			(at 307.34 200.66 0)
			(effects
				(font
					(size 1.27 1.27)
					(thickness 0.15)
				)
				(justify left bottom)
				(hide yes)
			)
		)
		(property "Datasheet" "https://www.bourns.com/docs/Product-Datasheets/SRP5030CA.pdf"
			(at 307.34 203.2 0)
			(effects
				(font
					(size 1.27 1.27)
					(thickness 0.15)
				)
				(justify left bottom)
				(hide yes)
			)
		)
		(property "Description" ""
			(at 293.37 193.04 0)
			(effects
				(font
					(size 1.27 1.27)
				)
				(hide yes)
			)
		)
		(property "Val" "560n/17.7A"
			(at 295.91 190.5 0)
			(effects
				(font
					(size 1.27 1.27)
					(thickness 0.15)
				)
			)
		)
		(property "Manufacturer" "Bourns"
			(at 307.34 205.74 0)
			(effects
				(font
					(size 1.27 1.27)
					(thickness 0.15)
				)
				(justify left bottom)
				(hide yes)
			)
		)
		(property "MPN" "SRP5030CA-R56M"
			(at 307.34 208.28 0)
			(effects
				(font
					(size 1.27 1.27)
					(thickness 0.15)
				)
				(justify left bottom)
				(hide yes)
			)
		)
		(property "ISat" "22.2 A"
			(at 307.34 209.55 0)
			(effects
				(font
					(size 1.27 1.27)
				)
				(justify left)
				(hide yes)
			)
		)
		(property "IMax" "17.7 A"
			(at 307.34 213.36 0)
			(effects
				(font
					(size 1.27 1.27)
					(thickness 0.15)
				)
				(justify left bottom)
				(hide yes)
			)
		)
		(property "Size" "5.5x5.3"
			(at 307.34 215.9 0)
			(effects
				(font
					(size 1.27 1.27)
					(thickness 0.15)
				)
				(justify left bottom)
				(hide yes)
			)
		)
		(property "Author" "Antmicro"
			(at 307.34 218.44 0)
			(effects
				(font
					(size 1.27 1.27)
					(thickness 0.15)
				)
				(justify left bottom)
				(hide yes)
			)
		)
		(property "License" "Apache-2.0"
			(at 307.34 220.98 0)
			(effects
				(font
					(size 1.27 1.27)
					(thickness 0.15)
				)
				(justify left bottom)
				(hide yes)
			)
		)
		(pin "2"
		)
		(pin "1"
		)
		(instances
			(project "jetson-orin-baseboard"
				(path ""
					(reference "L1")
					(unit 1)
				)
			)
		)
	)
	(symbol
		(lib_id "antmicropower:GND")
		(at 274.32 154.94 0)
		(unit 1)
		(exclude_from_sim no)
		(in_bom yes)
		(on_board yes)
		(dnp no)
		(property "Reference" "#PWR0186"
			(at 274.32 161.29 0)
			(effects
				(font
					(size 1.27 1.27)
				)
				(justify left bottom)
				(hide yes)
			)
		)
		(property "Value" "GND"
			(at 274.32 158.75 0)
			(effects
				(font
					(size 1.27 1.27)
					(thickness 0.15)
				)
			)
		)
		(property "Footprint" ""
			(at 283.21 162.56 0)
			(effects
				(font
					(size 1.27 1.27)
					(thickness 0.15)
				)
				(justify left bottom)
				(hide yes)
			)
		)
		(property "Datasheet" ""
			(at 283.21 167.64 0)
			(effects
				(font
					(size 1.27 1.27)
					(thickness 0.15)
				)
				(justify left bottom)
				(hide yes)
			)
		)
		(property "Description" ""
			(at 274.32 154.94 0)
			(effects
				(font
					(size 1.27 1.27)
				)
				(hide yes)
			)
		)
		(property "Author" "Antmicro"
			(at 283.21 162.56 0)
			(effects
				(font
					(size 1.27 1.27)
					(thickness 0.15)
				)
				(justify left bottom)
				(hide yes)
			)
		)
		(property "License" "Apache-2.0"
			(at 283.21 165.1 0)
			(effects
				(font
					(size 1.27 1.27)
					(thickness 0.15)
				)
				(justify left bottom)
				(hide yes)
			)
		)
		(pin "1"
		)
		(instances
			(project "jetson-orin-baseboard"
				(path ""
					(reference "#PWR0186")
					(unit 1)
				)
			)
		)
	)
	(symbol
		(lib_id "antmicroResistors0402:R_499k_0402")
		(at 223.52 212.09 90)
		(unit 1)
		(exclude_from_sim no)
		(in_bom yes)
		(on_board yes)
		(dnp no)
		(property "Reference" "R173"
			(at 224.79 208.28 90)
			(effects
				(font
					(size 1.27 1.27)
					(thickness 0.15)
				)
				(justify right)
			)
		)
		(property "Value" "R_499k_0402"
			(at 236.22 191.77 0)
			(effects
				(font
					(size 1.27 1.27)
					(thickness 0.15)
				)
				(justify left bottom)
				(hide yes)
			)
		)
		(property "Footprint" "antmicro-footprints:R_0402_1005Metric"
			(at 238.76 191.77 0)
			(effects
				(font
					(size 1.27 1.27)
					(thickness 0.15)
				)
				(justify left bottom)
				(hide yes)
			)
		)
		(property "Datasheet" "https://www.mouser.com/datasheet/2/54/cr-1858361.pdf"
			(at 241.3 191.77 0)
			(effects
				(font
					(size 1.27 1.27)
					(thickness 0.15)
				)
				(justify left bottom)
				(hide yes)
			)
		)
		(property "Description" ""
			(at 223.52 212.09 0)
			(effects
				(font
					(size 1.27 1.27)
				)
				(hide yes)
			)
		)
		(property "MPN" "CR0402-FX-4993GLF"
			(at 243.84 191.77 0)
			(effects
				(font
					(size 1.27 1.27)
					(thickness 0.15)
				)
				(justify left bottom)
				(hide yes)
			)
		)
		(property "Manufacturer" "Bourns"
			(at 246.38 191.77 0)
			(effects
				(font
					(size 1.27 1.27)
					(thickness 0.15)
				)
				(justify left bottom)
				(hide yes)
			)
		)
		(property "License" "Apache-2.0"
			(at 248.92 191.77 0)
			(effects
				(font
					(size 1.27 1.27)
					(thickness 0.15)
				)
				(justify left bottom)
				(hide yes)
			)
		)
		(property "Author" "Antmicro"
			(at 251.46 191.77 0)
			(effects
				(font
					(size 1.27 1.27)
					(thickness 0.15)
				)
				(justify left bottom)
				(hide yes)
			)
		)
		(property "Val" "499k"
			(at 224.79 210.82 90)
			(effects
				(font
					(size 1.27 1.27)
					(thickness 0.15)
				)
				(justify right)
			)
		)
		(property "Tolerance" "1%"
			(at 233.68 191.77 0)
			(effects
				(font
					(size 1.27 1.27)
				)
				(justify left bottom)
				(hide yes)
			)
		)
		(pin "2"
		)
		(pin "1"
		)
		(instances
			(project "jetson-orin-baseboard"
				(path ""
					(reference "R173")
					(unit 1)
				)
			)
		)
	)
	(symbol
		(lib_id "antmicroResistors0402:R_10k_0402")
		(at 203.2 238.76 90)
		(unit 1)
		(exclude_from_sim no)
		(in_bom yes)
		(on_board yes)
		(dnp no)
		(property "Reference" "R275"
			(at 204.47 234.9499 90)
			(effects
				(font
					(size 1.27 1.27)
				)
				(justify right)
			)
		)
		(property "Value" "R_10k_0402"
			(at 215.9 218.44 0)
			(effects
				(font
					(size 1.27 1.27)
					(thickness 0.15)
				)
				(justify left bottom)
				(hide yes)
			)
		)
		(property "Footprint" "antmicro-footprints:R_0402_1005Metric"
			(at 218.44 218.44 0)
			(effects
				(font
					(size 1.27 1.27)
					(thickness 0.15)
				)
				(justify left bottom)
				(hide yes)
			)
		)
		(property "Datasheet" "https://www.bourns.com/docs/product-datasheets/cr.pdf"
			(at 220.98 218.44 0)
			(effects
				(font
					(size 1.27 1.27)
					(thickness 0.15)
				)
				(justify left bottom)
				(hide yes)
			)
		)
		(property "Description" ""
			(at 203.2 238.76 0)
			(effects
				(font
					(size 1.27 1.27)
				)
				(hide yes)
			)
		)
		(property "Manufacturer" "Bourns"
			(at 226.06 218.44 0)
			(effects
				(font
					(size 1.27 1.27)
					(thickness 0.15)
				)
				(justify left bottom)
				(hide yes)
			)
		)
		(property "MPN" "CR0402-FX-1002GLF"
			(at 223.52 218.44 0)
			(effects
				(font
					(size 1.27 1.27)
					(thickness 0.15)
				)
				(justify left bottom)
				(hide yes)
			)
		)
		(property "Val" "10k"
			(at 204.47 237.49 90)
			(effects
				(font
					(size 1.27 1.27)
					(thickness 0.15)
				)
				(justify right)
			)
		)
		(property "License" "Apache-2.0"
			(at 228.6 218.44 0)
			(effects
				(font
					(size 1.27 1.27)
					(thickness 0.15)
				)
				(justify left bottom)
				(hide yes)
			)
		)
		(property "Author" "Antmicro"
			(at 231.14 218.44 0)
			(effects
				(font
					(size 1.27 1.27)
					(thickness 0.15)
				)
				(justify left bottom)
				(hide yes)
			)
		)
		(property "Tolerance" "1%"
			(at 213.36 218.44 0)
			(effects
				(font
					(size 1.27 1.27)
				)
				(justify left bottom)
				(hide yes)
			)
		)
		(pin "1"
		)
		(pin "2"
		)
		(instances
			(project "jetson-orin-baseboard"
				(path ""
					(reference "R275")
					(unit 1)
				)
			)
		)
	)
	(symbol
		(lib_id "antmicropower:PWR_FLAG")
		(at 346.71 116.84 0)
		(unit 1)
		(exclude_from_sim no)
		(in_bom yes)
		(on_board yes)
		(dnp no)
		(property "Reference" "#FLG04"
			(at 346.71 114.935 0)
			(effects
				(font
					(size 1.27 1.27)
				)
				(hide yes)
			)
		)
		(property "Value" "PWR_FLAG"
			(at 346.71 113.03 0)
			(effects
				(font
					(size 1.27 1.27)
				)
			)
		)
		(property "Footprint" ""
			(at 346.71 116.84 0)
			(effects
				(font
					(size 1.27 1.27)
				)
				(hide yes)
			)
		)
		(property "Datasheet" ""
			(at 346.71 116.84 0)
			(effects
				(font
					(size 1.27 1.27)
				)
				(hide yes)
			)
		)
		(property "Description" ""
			(at 346.71 116.84 0)
			(effects
				(font
					(size 1.27 1.27)
				)
				(hide yes)
			)
		)
		(pin "1"
		)
		(instances
			(project "jetson-orin-baseboard"
				(path ""
					(reference "#FLG04")
					(unit 1)
				)
			)
		)
	)
	(symbol
		(lib_id "antmicroCapacitorsmisc:C_22u_25V_0805")
		(at 198.12 205.74 90)
		(unit 1)
		(exclude_from_sim no)
		(in_bom yes)
		(on_board yes)
		(dnp no)
		(property "Reference" "C151"
			(at 198.755 201.295 90)
			(effects
				(font
					(size 1.27 1.27)
					(thickness 0.15)
				)
				(justify right)
			)
		)
		(property "Value" "C_22u_25V_0805"
			(at 208.28 185.42 0)
			(effects
				(font
					(size 1.27 1.27)
					(thickness 0.15)
				)
				(justify left bottom)
				(hide yes)
			)
		)
		(property "Footprint" "antmicro-footprints:C_0805_2012Metric"
			(at 210.82 185.42 0)
			(effects
				(font
					(size 1.27 1.27)
					(thickness 0.15)
				)
				(justify left bottom)
				(hide yes)
			)
		)
		(property "Datasheet" "https://product.samsungsem.com/mlcc/CL21A226MAYNNN.do"
			(at 213.36 185.42 0)
			(effects
				(font
					(size 1.27 1.27)
					(thickness 0.15)
				)
				(justify left bottom)
				(hide yes)
			)
		)
		(property "Description" ""
			(at 198.12 205.74 0)
			(effects
				(font
					(size 1.27 1.27)
				)
				(hide yes)
			)
		)
		(property "MPN" "CL21A226MAYNNNE"
			(at 215.9 185.42 0)
			(effects
				(font
					(size 1.27 1.27)
					(thickness 0.15)
				)
				(justify left bottom)
				(hide yes)
			)
		)
		(property "Manufacturer" "Samsung Electro-Mechanics"
			(at 218.44 185.42 0)
			(effects
				(font
					(size 1.27 1.27)
					(thickness 0.15)
				)
				(justify left bottom)
				(hide yes)
			)
		)
		(property "License" "Apache-2.0"
			(at 220.98 185.42 0)
			(effects
				(font
					(size 1.27 1.27)
					(thickness 0.15)
				)
				(justify left bottom)
				(hide yes)
			)
		)
		(property "Author" "Antmicro"
			(at 223.52 185.42 0)
			(effects
				(font
					(size 1.27 1.27)
					(thickness 0.15)
				)
				(justify left bottom)
				(hide yes)
			)
		)
		(property "Val" "22u"
			(at 198.755 205.105 90)
			(effects
				(font
					(size 1.27 1.27)
					(thickness 0.15)
				)
				(justify right)
			)
		)
		(property "Voltage" "25V"
			(at 198.755 207.01 90)
			(effects
				(font
					(size 1.27 1.27)
				)
				(justify right)
			)
		)
		(property "Dielectric" "X5R"
			(at 228.6 185.42 0)
			(effects
				(font
					(size 1.27 1.27)
				)
				(justify left bottom)
				(hide yes)
			)
		)
		(property "Public" "False"
			(at 231.14 185.42 0)
			(effects
				(font
					(size 1.27 1.27)
				)
				(justify left bottom)
				(hide yes)
			)
		)
		(pin "1"
		)
		(pin "2"
		)
		(instances
			(project "jetson-orin-baseboard"
				(path ""
					(reference "C151")
					(unit 1)
				)
			)
		)
	)
	(symbol
		(lib_id "antmicroResistors0402:R_200R_0402")
		(at 167.64 78.74 180)
		(unit 1)
		(exclude_from_sim no)
		(in_bom yes)
		(on_board yes)
		(dnp no)
		(property "Reference" "R236"
			(at 167.64 78.105 0)
			(effects
				(font
					(size 1.27 1.27)
				)
				(justify right top)
			)
		)
		(property "Value" "R_200R_0402"
			(at 147.32 66.04 0)
			(effects
				(font
					(size 1.27 1.27)
					(thickness 0.15)
				)
				(justify left bottom)
				(hide yes)
			)
		)
		(property "Footprint" "antmicro-footprints:R_0402_1005Metric"
			(at 147.32 63.5 0)
			(effects
				(font
					(size 1.27 1.27)
					(thickness 0.15)
				)
				(justify left bottom)
				(hide yes)
			)
		)
		(property "Datasheet" "https://www.bourns.com/docs/product-datasheets/cr.pdf"
			(at 147.32 60.96 0)
			(effects
				(font
					(size 1.27 1.27)
					(thickness 0.15)
				)
				(justify left bottom)
				(hide yes)
			)
		)
		(property "Description" ""
			(at 167.64 78.74 0)
			(effects
				(font
					(size 1.27 1.27)
				)
				(hide yes)
			)
		)
		(property "Manufacturer" "Bourns"
			(at 147.32 55.88 0)
			(effects
				(font
					(size 1.27 1.27)
					(thickness 0.15)
				)
				(justify left bottom)
				(hide yes)
			)
		)
		(property "MPN" "CR0402-FX-2000GLF"
			(at 147.32 58.42 0)
			(effects
				(font
					(size 1.27 1.27)
					(thickness 0.15)
				)
				(justify left bottom)
				(hide yes)
			)
		)
		(property "Val" "200R"
			(at 157.48 78.105 0)
			(effects
				(font
					(size 1.27 1.27)
					(thickness 0.15)
				)
				(justify right top)
			)
		)
		(property "License" "Apache-2.0"
			(at 147.32 53.34 0)
			(effects
				(font
					(size 1.27 1.27)
					(thickness 0.15)
				)
				(justify left bottom)
				(hide yes)
			)
		)
		(property "Author" "Antmicro"
			(at 147.32 50.8 0)
			(effects
				(font
					(size 1.27 1.27)
					(thickness 0.15)
				)
				(justify left bottom)
				(hide yes)
			)
		)
		(property "Tolerance" "1%"
			(at 147.32 68.58 0)
			(effects
				(font
					(size 1.27 1.27)
				)
				(justify left bottom)
				(hide yes)
			)
		)
		(pin "1"
		)
		(pin "2"
		)
		(instances
			(project "jetson-orin-baseboard"
				(path ""
					(reference "R236")
					(unit 1)
				)
			)
		)
	)
	(symbol
		(lib_id "antmicroResistors0603:R_0R_22.4A_0603")
		(at 58.42 209.55 0)
		(unit 1)
		(exclude_from_sim no)
		(in_bom yes)
		(on_board yes)
		(dnp no)
		(property "Reference" "R252"
			(at 63.5 208.915 0)
			(effects
				(font
					(size 1.27 1.27)
				)
				(justify left bottom)
			)
		)
		(property "Value" "R_0R_22.4A_0603"
			(at 60.96 200.66 0)
			(effects
				(font
					(size 1.27 1.27)
					(thickness 0.15)
				)
				(hide yes)
			)
		)
		(property "Footprint" "antmicro-footprints:R_0603_1608Metric"
			(at 73.66 219.71 0)
			(effects
				(font
					(size 1.27 1.27)
					(thickness 0.15)
				)
				(justify left bottom)
				(hide yes)
			)
		)
		(property "Datasheet" "https://fscdn.rohm.com/en/products/databook/datasheet/passive/resistor/chip_resistor/pmr-jpw-e.pdf"
			(at 73.66 222.25 0)
			(effects
				(font
					(size 1.27 1.27)
					(thickness 0.15)
				)
				(justify left bottom)
				(hide yes)
			)
		)
		(property "Description" ""
			(at 58.42 209.55 0)
			(effects
				(font
					(size 1.27 1.27)
				)
				(hide yes)
			)
		)
		(property "Manufacturer" "ROHM Semiconductor"
			(at 73.66 227.33 0)
			(effects
				(font
					(size 1.27 1.27)
					(thickness 0.15)
				)
				(justify left bottom)
				(hide yes)
			)
		)
		(property "MPN" "PMR03EZPJ000"
			(at 73.66 224.79 0)
			(effects
				(font
					(size 1.27 1.27)
					(thickness 0.15)
				)
				(justify left bottom)
				(hide yes)
			)
		)
		(property "Val" "0R"
			(at 55.88 208.915 0)
			(effects
				(font
					(size 1.27 1.27)
					(thickness 0.15)
				)
				(justify left bottom)
			)
		)
		(property "Author" "Antmicro"
			(at 73.66 232.41 0)
			(effects
				(font
					(size 1.27 1.27)
					(thickness 0.15)
				)
				(justify left bottom)
				(hide yes)
			)
		)
		(property "License" "Apache-2.0"
			(at 73.66 234.95 0)
			(effects
				(font
					(size 1.27 1.27)
					(thickness 0.15)
				)
				(justify left bottom)
				(hide yes)
			)
		)
		(property "Max. Curr." "22.4A"
			(at 60.96 211.455 0)
			(effects
				(font
					(size 1.27 1.27)
					(thickness 0.15)
				)
			)
		)
		(property "Tolerance" "template_tolerance"
			(at 78.74 219.71 0)
			(effects
				(font
					(size 1.27 1.27)
				)
				(justify left bottom)
				(hide yes)
			)
		)
		(pin "1"
		)
		(pin "2"
		)
		(instances
			(project "jetson-orin-baseboard"
				(path ""
					(reference "R252")
					(unit 1)
				)
			)
		)
	)
	(symbol
		(lib_id "antmicropower:GND")
		(at 189.23 154.94 0)
		(unit 1)
		(exclude_from_sim no)
		(in_bom yes)
		(on_board yes)
		(dnp no)
		(property "Reference" "#PWR0266"
			(at 189.23 161.29 0)
			(effects
				(font
					(size 1.27 1.27)
				)
				(justify left bottom)
				(hide yes)
			)
		)
		(property "Value" "GND"
			(at 189.23 158.75 0)
			(effects
				(font
					(size 1.27 1.27)
					(thickness 0.15)
				)
			)
		)
		(property "Footprint" ""
			(at 198.12 162.56 0)
			(effects
				(font
					(size 1.27 1.27)
					(thickness 0.15)
				)
				(justify left bottom)
				(hide yes)
			)
		)
		(property "Datasheet" ""
			(at 198.12 167.64 0)
			(effects
				(font
					(size 1.27 1.27)
					(thickness 0.15)
				)
				(justify left bottom)
				(hide yes)
			)
		)
		(property "Description" ""
			(at 189.23 154.94 0)
			(effects
				(font
					(size 1.27 1.27)
				)
				(hide yes)
			)
		)
		(property "Author" "Antmicro"
			(at 198.12 162.56 0)
			(effects
				(font
					(size 1.27 1.27)
					(thickness 0.15)
				)
				(justify left bottom)
				(hide yes)
			)
		)
		(property "License" "Apache-2.0"
			(at 198.12 165.1 0)
			(effects
				(font
					(size 1.27 1.27)
					(thickness 0.15)
				)
				(justify left bottom)
				(hide yes)
			)
		)
		(pin "1"
		)
		(instances
			(project "jetson-orin-baseboard"
				(path ""
					(reference "#PWR0266")
					(unit 1)
				)
			)
		)
	)
	(symbol
		(lib_id "antmicropower:GND")
		(at 336.55 154.94 0)
		(unit 1)
		(exclude_from_sim no)
		(in_bom yes)
		(on_board yes)
		(dnp no)
		(property "Reference" "#PWR0317"
			(at 336.55 161.29 0)
			(effects
				(font
					(size 1.27 1.27)
				)
				(justify left bottom)
				(hide yes)
			)
		)
		(property "Value" "GND"
			(at 336.55 158.75 0)
			(effects
				(font
					(size 1.27 1.27)
					(thickness 0.15)
				)
			)
		)
		(property "Footprint" ""
			(at 345.44 162.56 0)
			(effects
				(font
					(size 1.27 1.27)
					(thickness 0.15)
				)
				(justify left bottom)
				(hide yes)
			)
		)
		(property "Datasheet" ""
			(at 345.44 167.64 0)
			(effects
				(font
					(size 1.27 1.27)
					(thickness 0.15)
				)
				(justify left bottom)
				(hide yes)
			)
		)
		(property "Description" ""
			(at 336.55 154.94 0)
			(effects
				(font
					(size 1.27 1.27)
				)
				(hide yes)
			)
		)
		(property "Author" "Antmicro"
			(at 345.44 162.56 0)
			(effects
				(font
					(size 1.27 1.27)
					(thickness 0.15)
				)
				(justify left bottom)
				(hide yes)
			)
		)
		(property "License" "Apache-2.0"
			(at 345.44 165.1 0)
			(effects
				(font
					(size 1.27 1.27)
					(thickness 0.15)
				)
				(justify left bottom)
				(hide yes)
			)
		)
		(pin "1"
		)
		(instances
			(project "jetson-orin-baseboard"
				(path ""
					(reference "#PWR0317")
					(unit 1)
				)
			)
		)
	)
	(symbol
		(lib_id "antmicropower:+3V3")
		(at 365.76 190.5 0)
		(unit 1)
		(exclude_from_sim no)
		(in_bom yes)
		(on_board yes)
		(dnp no)
		(property "Reference" "#PWR0292"
			(at 365.76 194.31 0)
			(effects
				(font
					(size 1.27 1.27)
				)
				(justify left bottom)
				(hide yes)
			)
		)
		(property "Value" "+3V3"
			(at 362.585 186.69 0)
			(effects
				(font
					(size 1.27 1.27)
					(thickness 0.15)
				)
				(justify left)
			)
		)
		(property "Footprint" ""
			(at 381 198.12 0)
			(effects
				(font
					(size 1.27 1.27)
					(thickness 0.15)
				)
				(justify left bottom)
				(hide yes)
			)
		)
		(property "Datasheet" ""
			(at 381 200.66 0)
			(effects
				(font
					(size 1.27 1.27)
					(thickness 0.15)
				)
				(justify left bottom)
				(hide yes)
			)
		)
		(property "Description" ""
			(at 365.76 190.5 0)
			(effects
				(font
					(size 1.27 1.27)
				)
				(hide yes)
			)
		)
		(property "Author" "Antmicro"
			(at 381 193.04 0)
			(effects
				(font
					(size 1.27 1.27)
					(thickness 0.15)
				)
				(justify left bottom)
				(hide yes)
			)
		)
		(property "License" "Apache-2.0"
			(at 381 195.58 0)
			(effects
				(font
					(size 1.27 1.27)
					(thickness 0.15)
				)
				(justify left bottom)
				(hide yes)
			)
		)
		(pin "1"
		)
		(instances
			(project "jetson-orin-baseboard"
				(path ""
					(reference "#PWR0292")
					(unit 1)
				)
			)
		)
	)
	(symbol
		(lib_id "antmicroTestPoints:TP_0.75mm_SMD")
		(at 172.72 180.34 90)
		(unit 1)
		(exclude_from_sim no)
		(in_bom no)
		(on_board yes)
		(dnp no)
		(property "Reference" "TP23"
			(at 173.355 177.165 90)
			(effects
				(font
					(size 1.27 1.27)
				)
				(justify right)
			)
		)
		(property "Value" "TP_0.75mm_SMD"
			(at 176.53 170.18 0)
			(effects
				(font
					(size 1.27 1.27)
					(thickness 0.15)
				)
				(justify left bottom)
				(hide yes)
			)
		)
		(property "Footprint" "antmicro-footprints:TP_SMD_0.75mm"
			(at 179.07 170.18 0)
			(effects
				(font
					(size 1.27 1.27)
					(thickness 0.15)
				)
				(justify left bottom)
				(hide yes)
			)
		)
		(property "Datasheet" ""
			(at 185.42 162.56 0)
			(effects
				(font
					(size 1.27 1.27)
					(thickness 0.15)
				)
				(justify left bottom)
				(hide yes)
			)
		)
		(property "Description" ""
			(at 172.72 180.34 0)
			(effects
				(font
					(size 1.27 1.27)
				)
				(hide yes)
			)
		)
		(property "MPN" ""
			(at 184.15 169.545 0)
			(effects
				(font
					(size 1.27 1.27)
					(thickness 0.15)
				)
				(justify left bottom)
				(hide yes)
			)
		)
		(property "Manufacturer" ""
			(at 179.07 169.545 0)
			(effects
				(font
					(size 1.27 1.27)
					(thickness 0.15)
				)
				(justify left bottom)
				(hide yes)
			)
		)
		(property "Author" "Antmicro"
			(at 181.61 170.18 0)
			(effects
				(font
					(size 1.27 1.27)
					(thickness 0.15)
				)
				(justify left bottom)
				(hide yes)
			)
		)
		(property "License" "Apache-2.0"
			(at 184.15 170.18 0)
			(effects
				(font
					(size 1.27 1.27)
					(thickness 0.15)
				)
				(justify left bottom)
				(hide yes)
			)
		)
		(pin "1"
		)
		(instances
			(project "jetson-orin-baseboard"
				(path ""
					(reference "TP23")
					(unit 1)
				)
			)
		)
	)
	(symbol
		(lib_id "antmicropower:GND")
		(at 132.08 181.61 0)
		(unit 1)
		(exclude_from_sim no)
		(in_bom yes)
		(on_board yes)
		(dnp no)
		(property "Reference" "#PWR0254"
			(at 132.08 187.96 0)
			(effects
				(font
					(size 1.27 1.27)
				)
				(justify left bottom)
				(hide yes)
			)
		)
		(property "Value" "GND"
			(at 132.08 185.42 0)
			(effects
				(font
					(size 1.27 1.27)
					(thickness 0.15)
				)
			)
		)
		(property "Footprint" ""
			(at 140.97 189.23 0)
			(effects
				(font
					(size 1.27 1.27)
					(thickness 0.15)
				)
				(justify left bottom)
				(hide yes)
			)
		)
		(property "Datasheet" ""
			(at 140.97 194.31 0)
			(effects
				(font
					(size 1.27 1.27)
					(thickness 0.15)
				)
				(justify left bottom)
				(hide yes)
			)
		)
		(property "Description" ""
			(at 132.08 181.61 0)
			(effects
				(font
					(size 1.27 1.27)
				)
				(hide yes)
			)
		)
		(property "Author" "Antmicro"
			(at 140.97 189.23 0)
			(effects
				(font
					(size 1.27 1.27)
					(thickness 0.15)
				)
				(justify left bottom)
				(hide yes)
			)
		)
		(property "License" "Apache-2.0"
			(at 140.97 191.77 0)
			(effects
				(font
					(size 1.27 1.27)
					(thickness 0.15)
				)
				(justify left bottom)
				(hide yes)
			)
		)
		(pin "1"
		)
		(instances
			(project "jetson-orin-baseboard"
				(path ""
					(reference "#PWR0254")
					(unit 1)
				)
			)
		)
	)
	(symbol
		(lib_id "antmicropower:GND")
		(at 60.96 81.28 0)
		(unit 1)
		(exclude_from_sim no)
		(in_bom yes)
		(on_board yes)
		(dnp no)
		(property "Reference" "#PWR0247"
			(at 60.96 87.63 0)
			(effects
				(font
					(size 1.27 1.27)
				)
				(justify left bottom)
				(hide yes)
			)
		)
		(property "Value" "GND"
			(at 60.96 85.09 0)
			(effects
				(font
					(size 1.27 1.27)
					(thickness 0.15)
				)
			)
		)
		(property "Footprint" ""
			(at 69.85 88.9 0)
			(effects
				(font
					(size 1.27 1.27)
					(thickness 0.15)
				)
				(justify left bottom)
				(hide yes)
			)
		)
		(property "Datasheet" ""
			(at 69.85 93.98 0)
			(effects
				(font
					(size 1.27 1.27)
					(thickness 0.15)
				)
				(justify left bottom)
				(hide yes)
			)
		)
		(property "Description" ""
			(at 60.96 81.28 0)
			(effects
				(font
					(size 1.27 1.27)
				)
				(hide yes)
			)
		)
		(property "Author" "Antmicro"
			(at 69.85 88.9 0)
			(effects
				(font
					(size 1.27 1.27)
					(thickness 0.15)
				)
				(justify left bottom)
				(hide yes)
			)
		)
		(property "License" "Apache-2.0"
			(at 69.85 91.44 0)
			(effects
				(font
					(size 1.27 1.27)
					(thickness 0.15)
				)
				(justify left bottom)
				(hide yes)
			)
		)
		(pin "1"
		)
		(instances
			(project "jetson-orin-baseboard"
				(path ""
					(reference "#PWR0247")
					(unit 1)
				)
			)
		)
	)
	(symbol
		(lib_id "antmicroCapacitors0603:C_22u_16V_0603")
		(at 321.31 207.01 90)
		(unit 1)
		(exclude_from_sim no)
		(in_bom yes)
		(on_board yes)
		(dnp no)
		(property "Reference" "C127"
			(at 321.945 202.565 90)
			(effects
				(font
					(size 1.27 1.27)
				)
				(justify right)
			)
		)
		(property "Value" "C_22u_16V_0603"
			(at 331.47 186.69 0)
			(effects
				(font
					(size 1.27 1.27)
					(thickness 0.15)
				)
				(justify left bottom)
				(hide yes)
			)
		)
		(property "Footprint" "antmicro-footprints:C_0603_1608Metric_EIA"
			(at 334.01 186.69 0)
			(effects
				(font
					(size 1.27 1.27)
					(thickness 0.15)
				)
				(justify left bottom)
				(hide yes)
			)
		)
		(property "Datasheet" "https://product.samsungsem.com/mlcc/CL10A226MO7JZN.do"
			(at 336.55 186.69 0)
			(effects
				(font
					(size 1.27 1.27)
					(thickness 0.15)
				)
				(justify left bottom)
				(hide yes)
			)
		)
		(property "Description" "SMD Multilayer Ceramic Capacitor"
			(at 321.31 207.01 0)
			(effects
				(font
					(size 1.27 1.27)
				)
				(hide yes)
			)
		)
		(property "Manufacturer" "Samsung Electro-Mechanics"
			(at 341.63 186.69 0)
			(effects
				(font
					(size 1.27 1.27)
					(thickness 0.15)
				)
				(justify left bottom)
				(hide yes)
			)
		)
		(property "MPN" "CL10A226MO7JZNC"
			(at 339.09 186.69 0)
			(effects
				(font
					(size 1.27 1.27)
					(thickness 0.15)
				)
				(justify left bottom)
				(hide yes)
			)
		)
		(property "Val" "22u"
			(at 321.945 206.375 90)
			(effects
				(font
					(size 1.27 1.27)
					(thickness 0.15)
				)
				(justify right)
			)
		)
		(property "License" "Apache-2.0"
			(at 344.17 186.69 0)
			(effects
				(font
					(size 1.27 1.27)
					(thickness 0.15)
				)
				(justify left bottom)
				(hide yes)
			)
		)
		(property "Author" "Antmicro"
			(at 346.71 186.69 0)
			(effects
				(font
					(size 1.27 1.27)
					(thickness 0.15)
				)
				(justify left bottom)
				(hide yes)
			)
		)
		(property "Voltage" "16V"
			(at 349.25 186.69 0)
			(effects
				(font
					(size 1.27 1.27)
				)
				(justify left bottom)
				(hide yes)
			)
		)
		(property "Dielectric" ""
			(at 351.79 186.69 0)
			(effects
				(font
					(size 1.27 1.27)
				)
				(justify left bottom)
				(hide yes)
			)
		)
		(pin "1"
		)
		(pin "2"
		)
		(instances
			(project "jetson-orin-baseboard"
				(path ""
					(reference "C127")
					(unit 1)
				)
			)
		)
	)
	(symbol
		(lib_id "antmicroResistors0402:R_20k_0402")
		(at 223.52 111.76 90)
		(unit 1)
		(exclude_from_sim no)
		(in_bom yes)
		(on_board yes)
		(dnp no)
		(fields_autoplaced yes)
		(property "Reference" "R263"
			(at 226.06 107.95 90)
			(effects
				(font
					(size 1.27 1.27)
					(thickness 0.15)
				)
				(justify right)
			)
		)
		(property "Value" "R_20k_0402"
			(at 236.22 91.44 0)
			(effects
				(font
					(size 1.27 1.27)
					(thickness 0.15)
				)
				(justify left bottom)
				(hide yes)
			)
		)
		(property "Footprint" "antmicro-footprints:R_0402_1005Metric"
			(at 238.76 91.44 0)
			(effects
				(font
					(size 1.27 1.27)
					(thickness 0.15)
				)
				(justify left bottom)
				(hide yes)
			)
		)
		(property "Datasheet" "https://www.bourns.com/docs/product-datasheets/cr.pdf"
			(at 241.3 91.44 0)
			(effects
				(font
					(size 1.27 1.27)
					(thickness 0.15)
				)
				(justify left bottom)
				(hide yes)
			)
		)
		(property "Description" "SMD Chip Resistor, 20 kohm, ± 1%, 62.5 mW, 0402 [1005 Metric], Thick Film, General Purpose"
			(at 223.52 111.76 0)
			(effects
				(font
					(size 1.27 1.27)
				)
				(hide yes)
			)
		)
		(property "MPN" "CR0402-FX-2002GLF"
			(at 243.84 91.44 0)
			(effects
				(font
					(size 1.27 1.27)
					(thickness 0.15)
				)
				(justify left bottom)
				(hide yes)
			)
		)
		(property "Manufacturer" "Bourns"
			(at 246.38 91.44 0)
			(effects
				(font
					(size 1.27 1.27)
					(thickness 0.15)
				)
				(justify left bottom)
				(hide yes)
			)
		)
		(property "License" "Apache-2.0"
			(at 248.92 91.44 0)
			(effects
				(font
					(size 1.27 1.27)
					(thickness 0.15)
				)
				(justify left bottom)
				(hide yes)
			)
		)
		(property "Author" "Antmicro"
			(at 251.46 91.44 0)
			(effects
				(font
					(size 1.27 1.27)
					(thickness 0.15)
				)
				(justify left bottom)
				(hide yes)
			)
		)
		(property "Val" "20k"
			(at 226.06 110.49 90)
			(effects
				(font
					(size 1.27 1.27)
					(thickness 0.15)
				)
				(justify right)
			)
		)
		(property "Tolerance" "1%"
			(at 233.68 91.44 0)
			(effects
				(font
					(size 1.27 1.27)
				)
				(justify left bottom)
				(hide yes)
			)
		)
		(pin "2"
		)
		(pin "1"
		)
		(instances
			(project ""
				(path ""
					(reference "R263")
					(unit 1)
				)
			)
		)
	)
	(symbol
		(lib_id "antmicroCapacitors0402:C_100n_0402")
		(at 288.29 187.96 180)
		(unit 1)
		(exclude_from_sim no)
		(in_bom yes)
		(on_board yes)
		(dnp no)
		(fields_autoplaced yes)
		(property "Reference" "C125"
			(at 285.7436 181.61 0)
			(effects
				(font
					(size 1.27 1.27)
				)
			)
		)
		(property "Value" "C_100n_0402"
			(at 267.97 177.8 0)
			(effects
				(font
					(size 1.27 1.27)
					(thickness 0.15)
				)
				(justify left bottom)
				(hide yes)
			)
		)
		(property "Footprint" "antmicro-footprints:C_0402_1005Metric"
			(at 267.97 175.26 0)
			(effects
				(font
					(size 1.27 1.27)
					(thickness 0.15)
				)
				(justify left bottom)
				(hide yes)
			)
		)
		(property "Datasheet" "https://www.murata.com/products/productdetail?partno=GRM155R61H104KE14%23"
			(at 267.97 172.72 0)
			(effects
				(font
					(size 1.27 1.27)
					(thickness 0.15)
				)
				(justify left bottom)
				(hide yes)
			)
		)
		(property "Description" ""
			(at 288.29 187.96 0)
			(effects
				(font
					(size 1.27 1.27)
				)
				(hide yes)
			)
		)
		(property "Manufacturer" "Murata"
			(at 267.97 167.64 0)
			(effects
				(font
					(size 1.27 1.27)
					(thickness 0.15)
				)
				(justify left bottom)
				(hide yes)
			)
		)
		(property "MPN" "GRM155R61H104KE14D"
			(at 267.97 170.18 0)
			(effects
				(font
					(size 1.27 1.27)
					(thickness 0.15)
				)
				(justify left bottom)
				(hide yes)
			)
		)
		(property "Val" "100n"
			(at 285.7436 184.15 0)
			(effects
				(font
					(size 1.27 1.27)
					(thickness 0.15)
				)
			)
		)
		(property "License" "Apache-2.0"
			(at 267.97 165.1 0)
			(effects
				(font
					(size 1.27 1.27)
					(thickness 0.15)
				)
				(justify left bottom)
				(hide yes)
			)
		)
		(property "Author" "Antmicro"
			(at 267.97 162.56 0)
			(effects
				(font
					(size 1.27 1.27)
					(thickness 0.15)
				)
				(justify left bottom)
				(hide yes)
			)
		)
		(property "Voltage" "50V"
			(at 267.97 160.02 0)
			(effects
				(font
					(size 1.27 1.27)
				)
				(justify left bottom)
				(hide yes)
			)
		)
		(property "Dielectric" "X5R"
			(at 267.97 157.48 0)
			(effects
				(font
					(size 1.27 1.27)
				)
				(justify left bottom)
				(hide yes)
			)
		)
		(pin "1"
		)
		(pin "2"
		)
		(instances
			(project "jetson-orin-baseboard"
				(path ""
					(reference "C125")
					(unit 1)
				)
			)
		)
	)
	(symbol
		(lib_id "antmicroCapacitors0402:C_100n_0402")
		(at 233.68 114.3 270)
		(unit 1)
		(exclude_from_sim no)
		(in_bom yes)
		(on_board yes)
		(dnp no)
		(property "Reference" "C157"
			(at 234.315 114.935 90)
			(effects
				(font
					(size 1.27 1.27)
				)
				(justify left)
			)
		)
		(property "Value" "C_100n_0402"
			(at 223.52 134.62 0)
			(effects
				(font
					(size 1.27 1.27)
					(thickness 0.15)
				)
				(justify left bottom)
				(hide yes)
			)
		)
		(property "Footprint" "antmicro-footprints:C_0402_1005Metric"
			(at 220.98 134.62 0)
			(effects
				(font
					(size 1.27 1.27)
					(thickness 0.15)
				)
				(justify left bottom)
				(hide yes)
			)
		)
		(property "Datasheet" "https://www.murata.com/products/productdetail?partno=GRM155R61H104KE14%23"
			(at 218.44 134.62 0)
			(effects
				(font
					(size 1.27 1.27)
					(thickness 0.15)
				)
				(justify left bottom)
				(hide yes)
			)
		)
		(property "Description" ""
			(at 233.68 114.3 0)
			(effects
				(font
					(size 1.27 1.27)
				)
				(hide yes)
			)
		)
		(property "Manufacturer" "Murata"
			(at 213.36 134.62 0)
			(effects
				(font
					(size 1.27 1.27)
					(thickness 0.15)
				)
				(justify left bottom)
				(hide yes)
			)
		)
		(property "MPN" "GRM155R61H104KE14D"
			(at 215.9 134.62 0)
			(effects
				(font
					(size 1.27 1.27)
					(thickness 0.15)
				)
				(justify left bottom)
				(hide yes)
			)
		)
		(property "Val" "100n"
			(at 234.315 118.745 90)
			(effects
				(font
					(size 1.27 1.27)
					(thickness 0.15)
				)
				(justify left)
			)
		)
		(property "License" "Apache-2.0"
			(at 210.82 134.62 0)
			(effects
				(font
					(size 1.27 1.27)
					(thickness 0.15)
				)
				(justify left bottom)
				(hide yes)
			)
		)
		(property "Author" "Antmicro"
			(at 208.28 134.62 0)
			(effects
				(font
					(size 1.27 1.27)
					(thickness 0.15)
				)
				(justify left bottom)
				(hide yes)
			)
		)
		(property "Voltage" "50V"
			(at 205.74 134.62 0)
			(effects
				(font
					(size 1.27 1.27)
				)
				(justify left bottom)
				(hide yes)
			)
		)
		(property "Dielectric" "X5R"
			(at 203.2 134.62 0)
			(effects
				(font
					(size 1.27 1.27)
				)
				(justify left bottom)
				(hide yes)
			)
		)
		(pin "1"
		)
		(pin "2"
		)
		(instances
			(project "jetson-orin-baseboard"
				(path ""
					(reference "C157")
					(unit 1)
				)
			)
		)
	)
	(symbol
		(lib_id "antmicroDCDCConverters:SIC431AED-T1-GE3")
		(at 251.46 187.96 0)
		(unit 1)
		(exclude_from_sim no)
		(in_bom yes)
		(on_board yes)
		(dnp no)
		(property "Reference" "U40"
			(at 261.62 181.61 0)
			(effects
				(font
					(size 1.27 1.27)
					(thickness 0.15)
				)
			)
		)
		(property "Value" "SIC431AED-T1-GE3"
			(at 284.48 195.58 0)
			(effects
				(font
					(size 1.27 1.27)
					(thickness 0.15)
				)
				(justify left bottom)
				(hide yes)
			)
		)
		(property "Footprint" "antmicro-footprints:MLP44-24L_4x4x0.75mm"
			(at 284.48 198.12 0)
			(effects
				(font
					(size 1.27 1.27)
					(thickness 0.15)
				)
				(justify left bottom)
				(hide yes)
			)
		)
		(property "Datasheet" "https://www.vishay.com/docs/74589/sic431.pdf"
			(at 284.48 200.66 0)
			(effects
				(font
					(size 1.27 1.27)
					(thickness 0.15)
				)
				(justify left bottom)
				(hide yes)
			)
		)
		(property "Description" ""
			(at 251.46 187.96 0)
			(effects
				(font
					(size 1.27 1.27)
				)
				(hide yes)
			)
		)
		(property "Manufacturer" "Vishay"
			(at 284.48 203.2 0)
			(effects
				(font
					(size 1.27 1.27)
					(thickness 0.15)
				)
				(justify left bottom)
				(hide yes)
			)
		)
		(property "MPN" "SIC431AED-T1-GE3 "
			(at 262.89 184.15 0)
			(effects
				(font
					(size 1.27 1.27)
					(thickness 0.15)
				)
			)
		)
		(property "Author" "Antmicro"
			(at 284.48 205.74 0)
			(effects
				(font
					(size 1.27 1.27)
					(thickness 0.15)
				)
				(justify left bottom)
				(hide yes)
			)
		)
		(property "License" "Apache-2.0"
			(at 284.48 208.28 0)
			(effects
				(font
					(size 1.27 1.27)
					(thickness 0.15)
				)
				(justify left bottom)
				(hide yes)
			)
		)
		(pin "7"
		)
		(pin "16"
		)
		(pin "18"
		)
		(pin "8"
		)
		(pin "15"
		)
		(pin "14"
		)
		(pin "20"
		)
		(pin "2"
		)
		(pin "12"
		)
		(pin "22"
		)
		(pin "11"
		)
		(pin "26"
		)
		(pin "10"
		)
		(pin "19"
		)
		(pin "5"
		)
		(pin "4"
		)
		(pin "17"
		)
		(pin "6"
		)
		(pin "3"
		)
		(pin "1"
		)
		(pin "13"
		)
		(pin "23"
		)
		(pin "25"
		)
		(pin "21"
		)
		(pin "24"
		)
		(pin "9"
		)
		(pin "27"
		)
		(pin "28"
		)
		(instances
			(project "jetson-orin-baseboard"
				(path ""
					(reference "U40")
					(unit 1)
				)
			)
		)
	)
	(symbol
		(lib_id "antmicropower:GND")
		(at 365.76 78.74 0)
		(unit 1)
		(exclude_from_sim no)
		(in_bom yes)
		(on_board yes)
		(dnp no)
		(property "Reference" "#PWR0281"
			(at 365.76 85.09 0)
			(effects
				(font
					(size 1.27 1.27)
				)
				(justify left bottom)
				(hide yes)
			)
		)
		(property "Value" "GND"
			(at 365.76 82.55 0)
			(effects
				(font
					(size 1.27 1.27)
					(thickness 0.15)
				)
			)
		)
		(property "Footprint" ""
			(at 374.65 86.36 0)
			(effects
				(font
					(size 1.27 1.27)
					(thickness 0.15)
				)
				(justify left bottom)
				(hide yes)
			)
		)
		(property "Datasheet" ""
			(at 374.65 91.44 0)
			(effects
				(font
					(size 1.27 1.27)
					(thickness 0.15)
				)
				(justify left bottom)
				(hide yes)
			)
		)
		(property "Description" ""
			(at 365.76 78.74 0)
			(effects
				(font
					(size 1.27 1.27)
				)
				(hide yes)
			)
		)
		(property "Author" "Antmicro"
			(at 374.65 86.36 0)
			(effects
				(font
					(size 1.27 1.27)
					(thickness 0.15)
				)
				(justify left bottom)
				(hide yes)
			)
		)
		(property "License" "Apache-2.0"
			(at 374.65 88.9 0)
			(effects
				(font
					(size 1.27 1.27)
					(thickness 0.15)
				)
				(justify left bottom)
				(hide yes)
			)
		)
		(pin "1"
		)
		(instances
			(project "jetson-orin-baseboard"
				(path ""
					(reference "#PWR0281")
					(unit 1)
				)
			)
		)
	)
	(symbol
		(lib_id "antmicroResistors0402:R_100k_0402")
		(at 35.56 80.01 90)
		(unit 1)
		(exclude_from_sim no)
		(in_bom yes)
		(on_board yes)
		(dnp no)
		(property "Reference" "R249"
			(at 36.83 76.2 90)
			(effects
				(font
					(size 1.27 1.27)
				)
				(justify right)
			)
		)
		(property "Value" "R_100k_0402"
			(at 48.26 59.69 0)
			(effects
				(font
					(size 1.27 1.27)
					(thickness 0.15)
				)
				(justify left bottom)
				(hide yes)
			)
		)
		(property "Footprint" "antmicro-footprints:R_0402_1005Metric"
			(at 50.8 59.69 0)
			(effects
				(font
					(size 1.27 1.27)
					(thickness 0.15)
				)
				(justify left bottom)
				(hide yes)
			)
		)
		(property "Datasheet" "https://www.bourns.com/docs/product-datasheets/cr.pdf"
			(at 53.34 59.69 0)
			(effects
				(font
					(size 1.27 1.27)
					(thickness 0.15)
				)
				(justify left bottom)
				(hide yes)
			)
		)
		(property "Description" ""
			(at 35.56 80.01 0)
			(effects
				(font
					(size 1.27 1.27)
				)
				(hide yes)
			)
		)
		(property "Manufacturer" "Bourns"
			(at 58.42 59.69 0)
			(effects
				(font
					(size 1.27 1.27)
					(thickness 0.15)
				)
				(justify left bottom)
				(hide yes)
			)
		)
		(property "MPN" "CR0402-FX-1003GLF"
			(at 55.88 59.69 0)
			(effects
				(font
					(size 1.27 1.27)
					(thickness 0.15)
				)
				(justify left bottom)
				(hide yes)
			)
		)
		(property "Val" "100k"
			(at 36.83 78.74 90)
			(effects
				(font
					(size 1.27 1.27)
					(thickness 0.15)
				)
				(justify right)
			)
		)
		(property "License" "Apache-2.0"
			(at 60.96 59.69 0)
			(effects
				(font
					(size 1.27 1.27)
					(thickness 0.15)
				)
				(justify left bottom)
				(hide yes)
			)
		)
		(property "Author" "Antmicro"
			(at 63.5 59.69 0)
			(effects
				(font
					(size 1.27 1.27)
					(thickness 0.15)
				)
				(justify left bottom)
				(hide yes)
			)
		)
		(property "Tolerance" "1%"
			(at 45.72 59.69 0)
			(effects
				(font
					(size 1.27 1.27)
				)
				(justify left bottom)
				(hide yes)
			)
		)
		(pin "1"
		)
		(pin "2"
		)
		(instances
			(project "jetson-orin-baseboard"
				(path ""
					(reference "R249")
					(unit 1)
				)
			)
		)
	)
	(symbol
		(lib_id "antmicroResistors0603:R_0R_0603")
		(at 365.76 30.48 0)
		(unit 1)
		(exclude_from_sim no)
		(in_bom yes)
		(on_board yes)
		(dnp no)
		(property "Reference" "R273"
			(at 370.84 29.845 0)
			(effects
				(font
					(size 1.27 1.27)
				)
				(justify left bottom)
			)
		)
		(property "Value" "R_0R_0603"
			(at 386.08 43.18 0)
			(effects
				(font
					(size 1.27 1.27)
					(thickness 0.15)
				)
				(justify left bottom)
				(hide yes)
			)
		)
		(property "Footprint" "antmicro-footprints:R_0603_1608Metric"
			(at 386.08 45.72 0)
			(effects
				(font
					(size 1.27 1.27)
					(thickness 0.15)
				)
				(justify left bottom)
				(hide yes)
			)
		)
		(property "Datasheet" "https://www.bourns.com/docs/product-datasheets/cr.pdf?sfvrsn=574d41f6_14"
			(at 386.08 48.26 0)
			(effects
				(font
					(size 1.27 1.27)
					(thickness 0.15)
				)
				(justify left bottom)
				(hide yes)
			)
		)
		(property "Description" ""
			(at 365.76 30.48 0)
			(effects
				(font
					(size 1.27 1.27)
				)
				(hide yes)
			)
		)
		(property "Manufacturer" "Bourns"
			(at 386.08 53.34 0)
			(effects
				(font
					(size 1.27 1.27)
					(thickness 0.15)
				)
				(justify left bottom)
				(hide yes)
			)
		)
		(property "MPN" "CR0603-J/-000ELF"
			(at 386.08 50.8 0)
			(effects
				(font
					(size 1.27 1.27)
					(thickness 0.15)
				)
				(justify left bottom)
				(hide yes)
			)
		)
		(property "Val" "0R"
			(at 363.22 29.845 0)
			(effects
				(font
					(size 1.27 1.27)
					(thickness 0.15)
				)
				(justify left bottom)
			)
		)
		(property "License" "Apache-2.0"
			(at 386.08 55.88 0)
			(effects
				(font
					(size 1.27 1.27)
					(thickness 0.15)
				)
				(justify left bottom)
				(hide yes)
			)
		)
		(property "Author" "Antmicro"
			(at 386.08 58.42 0)
			(effects
				(font
					(size 1.27 1.27)
					(thickness 0.15)
				)
				(justify left bottom)
				(hide yes)
			)
		)
		(property "Tolerance" "~"
			(at 386.08 40.64 0)
			(effects
				(font
					(size 1.27 1.27)
				)
				(justify left bottom)
				(hide yes)
			)
		)
		(property "Current" "1A"
			(at 386.08 60.96 0)
			(effects
				(font
					(size 1.27 1.27)
					(thickness 0.15)
				)
				(justify left bottom)
				(hide yes)
			)
		)
		(pin "1"
		)
		(pin "2"
		)
		(instances
			(project "jetson-orin-baseboard"
				(path ""
					(reference "R273")
					(unit 1)
				)
			)
		)
	)
	(symbol
		(lib_id "antmicropower:+5V")
		(at 358.14 116.84 0)
		(unit 1)
		(exclude_from_sim no)
		(in_bom yes)
		(on_board yes)
		(dnp no)
		(property "Reference" "#PWR0373"
			(at 358.14 120.65 0)
			(effects
				(font
					(size 1.27 1.27)
				)
				(justify left bottom)
				(hide yes)
			)
		)
		(property "Value" "+5V_SoM"
			(at 358.14 113.03 0)
			(effects
				(font
					(size 1.27 1.27)
					(thickness 0.15)
				)
			)
		)
		(property "Footprint" ""
			(at 373.38 124.46 0)
			(effects
				(font
					(size 1.27 1.27)
					(thickness 0.15)
				)
				(justify left bottom)
				(hide yes)
			)
		)
		(property "Datasheet" ""
			(at 373.38 127 0)
			(effects
				(font
					(size 1.27 1.27)
					(thickness 0.15)
				)
				(justify left bottom)
				(hide yes)
			)
		)
		(property "Description" ""
			(at 358.14 116.84 0)
			(effects
				(font
					(size 1.27 1.27)
				)
				(hide yes)
			)
		)
		(property "Author" "Antmicro"
			(at 373.38 124.46 0)
			(effects
				(font
					(size 1.27 1.27)
					(thickness 0.15)
				)
				(justify left bottom)
				(hide yes)
			)
		)
		(property "License" "Apache-2.0"
			(at 373.38 127 0)
			(effects
				(font
					(size 1.27 1.27)
					(thickness 0.15)
				)
				(justify left bottom)
				(hide yes)
			)
		)
		(pin "1"
		)
		(instances
			(project "jetson-orin-baseboard"
				(path ""
					(reference "#PWR0373")
					(unit 1)
				)
			)
		)
	)
	(symbol
		(lib_id "antmicropower:GND")
		(at 374.65 156.21 0)
		(unit 1)
		(exclude_from_sim no)
		(in_bom yes)
		(on_board yes)
		(dnp no)
		(property "Reference" "#PWR0288"
			(at 374.65 162.56 0)
			(effects
				(font
					(size 1.27 1.27)
				)
				(justify left bottom)
				(hide yes)
			)
		)
		(property "Value" "GND"
			(at 374.65 160.02 0)
			(effects
				(font
					(size 1.27 1.27)
					(thickness 0.15)
				)
			)
		)
		(property "Footprint" ""
			(at 383.54 163.83 0)
			(effects
				(font
					(size 1.27 1.27)
					(thickness 0.15)
				)
				(justify left bottom)
				(hide yes)
			)
		)
		(property "Datasheet" ""
			(at 383.54 168.91 0)
			(effects
				(font
					(size 1.27 1.27)
					(thickness 0.15)
				)
				(justify left bottom)
				(hide yes)
			)
		)
		(property "Description" ""
			(at 374.65 156.21 0)
			(effects
				(font
					(size 1.27 1.27)
				)
				(hide yes)
			)
		)
		(property "Author" "Antmicro"
			(at 383.54 163.83 0)
			(effects
				(font
					(size 1.27 1.27)
					(thickness 0.15)
				)
				(justify left bottom)
				(hide yes)
			)
		)
		(property "License" "Apache-2.0"
			(at 383.54 166.37 0)
			(effects
				(font
					(size 1.27 1.27)
					(thickness 0.15)
				)
				(justify left bottom)
				(hide yes)
			)
		)
		(pin "1"
		)
		(instances
			(project "jetson-orin-baseboard"
				(path ""
					(reference "#PWR0288")
					(unit 1)
				)
			)
		)
	)
	(symbol
		(lib_id "antmicropower:GND")
		(at 318.77 38.1 0)
		(unit 1)
		(exclude_from_sim no)
		(in_bom yes)
		(on_board yes)
		(dnp no)
		(property "Reference" "#PWR0249"
			(at 318.77 44.45 0)
			(effects
				(font
					(size 1.27 1.27)
				)
				(justify left bottom)
				(hide yes)
			)
		)
		(property "Value" "GND"
			(at 318.77 41.91 0)
			(effects
				(font
					(size 1.27 1.27)
					(thickness 0.15)
				)
			)
		)
		(property "Footprint" ""
			(at 327.66 45.72 0)
			(effects
				(font
					(size 1.27 1.27)
					(thickness 0.15)
				)
				(justify left bottom)
				(hide yes)
			)
		)
		(property "Datasheet" ""
			(at 327.66 50.8 0)
			(effects
				(font
					(size 1.27 1.27)
					(thickness 0.15)
				)
				(justify left bottom)
				(hide yes)
			)
		)
		(property "Description" ""
			(at 318.77 38.1 0)
			(effects
				(font
					(size 1.27 1.27)
				)
				(hide yes)
			)
		)
		(property "Author" "Antmicro"
			(at 327.66 45.72 0)
			(effects
				(font
					(size 1.27 1.27)
					(thickness 0.15)
				)
				(justify left bottom)
				(hide yes)
			)
		)
		(property "License" "Apache-2.0"
			(at 327.66 48.26 0)
			(effects
				(font
					(size 1.27 1.27)
					(thickness 0.15)
				)
				(justify left bottom)
				(hide yes)
			)
		)
		(pin "1"
		)
		(instances
			(project "jetson-orin-baseboard"
				(path ""
					(reference "#PWR0249")
					(unit 1)
				)
			)
		)
	)
	(symbol
		(lib_id "antmicropower:PWR_FLAG")
		(at 382.27 26.67 0)
		(unit 1)
		(exclude_from_sim no)
		(in_bom yes)
		(on_board yes)
		(dnp no)
		(property "Reference" "#FLG01"
			(at 382.27 24.765 0)
			(effects
				(font
					(size 1.27 1.27)
				)
				(hide yes)
			)
		)
		(property "Value" "PWR_FLAG"
			(at 382.27 22.86 0)
			(effects
				(font
					(size 1.27 1.27)
				)
			)
		)
		(property "Footprint" ""
			(at 382.27 26.67 0)
			(effects
				(font
					(size 1.27 1.27)
				)
				(hide yes)
			)
		)
		(property "Datasheet" ""
			(at 382.27 26.67 0)
			(effects
				(font
					(size 1.27 1.27)
				)
				(hide yes)
			)
		)
		(property "Description" ""
			(at 382.27 26.67 0)
			(effects
				(font
					(size 1.27 1.27)
				)
				(hide yes)
			)
		)
		(pin "1"
		)
		(instances
			(project "jetson-orin-baseboard"
				(path ""
					(reference "#FLG01")
					(unit 1)
				)
			)
		)
	)
	(symbol
		(lib_id "antmicropower:GND")
		(at 321.31 154.94 0)
		(unit 1)
		(exclude_from_sim no)
		(in_bom yes)
		(on_board yes)
		(dnp no)
		(property "Reference" "#PWR0195"
			(at 321.31 161.29 0)
			(effects
				(font
					(size 1.27 1.27)
				)
				(justify left bottom)
				(hide yes)
			)
		)
		(property "Value" "GND"
			(at 321.31 158.75 0)
			(effects
				(font
					(size 1.27 1.27)
					(thickness 0.15)
				)
			)
		)
		(property "Footprint" ""
			(at 330.2 162.56 0)
			(effects
				(font
					(size 1.27 1.27)
					(thickness 0.15)
				)
				(justify left bottom)
				(hide yes)
			)
		)
		(property "Datasheet" ""
			(at 330.2 167.64 0)
			(effects
				(font
					(size 1.27 1.27)
					(thickness 0.15)
				)
				(justify left bottom)
				(hide yes)
			)
		)
		(property "Description" ""
			(at 321.31 154.94 0)
			(effects
				(font
					(size 1.27 1.27)
				)
				(hide yes)
			)
		)
		(property "Author" "Antmicro"
			(at 330.2 162.56 0)
			(effects
				(font
					(size 1.27 1.27)
					(thickness 0.15)
				)
				(justify left bottom)
				(hide yes)
			)
		)
		(property "License" "Apache-2.0"
			(at 330.2 165.1 0)
			(effects
				(font
					(size 1.27 1.27)
					(thickness 0.15)
				)
				(justify left bottom)
				(hide yes)
			)
		)
		(pin "1"
		)
		(instances
			(project "jetson-orin-baseboard"
				(path ""
					(reference "#PWR0195")
					(unit 1)
				)
			)
		)
	)
	(symbol
		(lib_id "antmicroTestPoints:TP_0.75mm_SMD")
		(at 367.03 193.04 0)
		(unit 1)
		(exclude_from_sim no)
		(in_bom no)
		(on_board yes)
		(dnp no)
		(property "Reference" "TP54"
			(at 370.84 193.04 0)
			(effects
				(font
					(size 1.27 1.27)
				)
				(justify left)
			)
		)
		(property "Value" "TP_0.75mm_SMD"
			(at 377.19 196.85 0)
			(effects
				(font
					(size 1.27 1.27)
					(thickness 0.15)
				)
				(justify left bottom)
				(hide yes)
			)
		)
		(property "Footprint" "antmicro-footprints:TP_SMD_0.75mm"
			(at 377.19 199.39 0)
			(effects
				(font
					(size 1.27 1.27)
					(thickness 0.15)
				)
				(justify left bottom)
				(hide yes)
			)
		)
		(property "Datasheet" ""
			(at 384.81 205.74 0)
			(effects
				(font
					(size 1.27 1.27)
					(thickness 0.15)
				)
				(justify left bottom)
				(hide yes)
			)
		)
		(property "Description" ""
			(at 367.03 193.04 0)
			(effects
				(font
					(size 1.27 1.27)
				)
				(hide yes)
			)
		)
		(property "MPN" ""
			(at 377.825 204.47 0)
			(effects
				(font
					(size 1.27 1.27)
					(thickness 0.15)
				)
				(justify left bottom)
				(hide yes)
			)
		)
		(property "Manufacturer" ""
			(at 377.825 199.39 0)
			(effects
				(font
					(size 1.27 1.27)
					(thickness 0.15)
				)
				(justify left bottom)
				(hide yes)
			)
		)
		(property "Author" "Antmicro"
			(at 377.19 201.93 0)
			(effects
				(font
					(size 1.27 1.27)
					(thickness 0.15)
				)
				(justify left bottom)
				(hide yes)
			)
		)
		(property "License" "Apache-2.0"
			(at 377.19 204.47 0)
			(effects
				(font
					(size 1.27 1.27)
					(thickness 0.15)
				)
				(justify left bottom)
				(hide yes)
			)
		)
		(pin "1"
		)
		(instances
			(project "jetson-orin-baseboard"
				(path ""
					(reference "TP54")
					(unit 1)
				)
			)
		)
	)
	(symbol
		(lib_id "antmicropower:GND")
		(at 355.6 38.1 0)
		(unit 1)
		(exclude_from_sim no)
		(in_bom yes)
		(on_board yes)
		(dnp no)
		(property "Reference" "#PWR059"
			(at 355.6 44.45 0)
			(effects
				(font
					(size 1.27 1.27)
				)
				(justify left bottom)
				(hide yes)
			)
		)
		(property "Value" "GND"
			(at 355.6 41.91 0)
			(effects
				(font
					(size 1.27 1.27)
					(thickness 0.15)
				)
			)
		)
		(property "Footprint" ""
			(at 364.49 45.72 0)
			(effects
				(font
					(size 1.27 1.27)
					(thickness 0.15)
				)
				(justify left bottom)
				(hide yes)
			)
		)
		(property "Datasheet" ""
			(at 364.49 50.8 0)
			(effects
				(font
					(size 1.27 1.27)
					(thickness 0.15)
				)
				(justify left bottom)
				(hide yes)
			)
		)
		(property "Description" ""
			(at 355.6 38.1 0)
			(effects
				(font
					(size 1.27 1.27)
				)
				(hide yes)
			)
		)
		(property "Author" "Antmicro"
			(at 364.49 45.72 0)
			(effects
				(font
					(size 1.27 1.27)
					(thickness 0.15)
				)
				(justify left bottom)
				(hide yes)
			)
		)
		(property "License" "Apache-2.0"
			(at 364.49 48.26 0)
			(effects
				(font
					(size 1.27 1.27)
					(thickness 0.15)
				)
				(justify left bottom)
				(hide yes)
			)
		)
		(pin "1"
		)
		(instances
			(project "jetson-orin-baseboard"
				(path ""
					(reference "#PWR059")
					(unit 1)
				)
			)
		)
	)
	(symbol
		(lib_id "antmicroTransistorsFETsMOSFETsSingle:PJE138K")
		(at 261.62 49.53 0)
		(unit 1)
		(exclude_from_sim no)
		(in_bom yes)
		(on_board yes)
		(dnp no)
		(property "Reference" "Q8"
			(at 270.51 45.72 0)
			(effects
				(font
					(size 1.27 1.27)
					(thickness 0.15)
				)
				(justify left)
			)
		)
		(property "Value" "PJE138K"
			(at 284.48 58.42 0)
			(effects
				(font
					(size 1.27 1.27)
					(thickness 0.15)
				)
				(justify left bottom)
				(hide yes)
			)
		)
		(property "Footprint" "antmicro-footprints:SOT-523"
			(at 284.48 60.96 0)
			(effects
				(font
					(size 1.27 1.27)
					(thickness 0.15)
				)
				(justify left bottom)
				(hide yes)
			)
		)
		(property "Datasheet" "https://www.mouser.com/datasheet/2/1057/PJE138K-1876698.pdf"
			(at 284.48 63.5 0)
			(effects
				(font
					(size 1.27 1.27)
					(thickness 0.15)
				)
				(justify left bottom)
				(hide yes)
			)
		)
		(property "Description" ""
			(at 261.62 49.53 0)
			(effects
				(font
					(size 1.27 1.27)
				)
				(hide yes)
			)
		)
		(property "MPN" "PJE138K_R1_00001"
			(at 270.51 48.26 0)
			(effects
				(font
					(size 1.27 1.27)
					(thickness 0.15)
				)
				(justify left)
			)
		)
		(property "Manufacturer" "PANJIT"
			(at 284.48 68.58 0)
			(effects
				(font
					(size 1.27 1.27)
					(thickness 0.15)
				)
				(justify left bottom)
				(hide yes)
			)
		)
		(property "Author" "Antmicro"
			(at 284.48 71.12 0)
			(effects
				(font
					(size 1.27 1.27)
					(thickness 0.15)
				)
				(justify left bottom)
				(hide yes)
			)
		)
		(property "License" "Apache-2.0"
			(at 284.48 73.66 0)
			(effects
				(font
					(size 1.27 1.27)
					(thickness 0.15)
				)
				(justify left bottom)
				(hide yes)
			)
		)
		(pin "2"
		)
		(pin "3"
		)
		(pin "1"
		)
		(instances
			(project "jetson-orin-baseboard"
				(path ""
					(reference "Q8")
					(unit 1)
				)
			)
		)
	)
	(symbol
		(lib_id "antmicropower:GND")
		(at 172.72 34.29 0)
		(unit 1)
		(exclude_from_sim no)
		(in_bom yes)
		(on_board yes)
		(dnp no)
		(property "Reference" "#PWR0265"
			(at 172.72 40.64 0)
			(effects
				(font
					(size 1.27 1.27)
				)
				(justify left bottom)
				(hide yes)
			)
		)
		(property "Value" "GND"
			(at 172.72 38.1 0)
			(effects
				(font
					(size 1.27 1.27)
					(thickness 0.15)
				)
			)
		)
		(property "Footprint" ""
			(at 181.61 41.91 0)
			(effects
				(font
					(size 1.27 1.27)
					(thickness 0.15)
				)
				(justify left bottom)
				(hide yes)
			)
		)
		(property "Datasheet" ""
			(at 181.61 46.99 0)
			(effects
				(font
					(size 1.27 1.27)
					(thickness 0.15)
				)
				(justify left bottom)
				(hide yes)
			)
		)
		(property "Description" ""
			(at 172.72 34.29 0)
			(effects
				(font
					(size 1.27 1.27)
				)
				(hide yes)
			)
		)
		(property "Author" "Antmicro"
			(at 181.61 41.91 0)
			(effects
				(font
					(size 1.27 1.27)
					(thickness 0.15)
				)
				(justify left bottom)
				(hide yes)
			)
		)
		(property "License" "Apache-2.0"
			(at 181.61 44.45 0)
			(effects
				(font
					(size 1.27 1.27)
					(thickness 0.15)
				)
				(justify left bottom)
				(hide yes)
			)
		)
		(pin "1"
		)
		(instances
			(project "jetson-orin-baseboard"
				(path ""
					(reference "#PWR0265")
					(unit 1)
				)
			)
		)
	)
	(symbol
		(lib_id "antmicroPushbuttonSwitches:SW_KMR211NGLFS_SMD")
		(at 246.38 31.75 270)
		(unit 1)
		(exclude_from_sim no)
		(in_bom yes)
		(on_board yes)
		(dnp no)
		(property "Reference" "S5"
			(at 249.555 35.56 90)
			(effects
				(font
					(size 1.27 1.27)
				)
				(justify left)
			)
		)
		(property "Value" "SW_KMR211NGLFS_SMD"
			(at 238.76 57.15 0)
			(effects
				(font
					(size 1.27 1.27)
					(thickness 0.15)
				)
				(justify left bottom)
				(hide yes)
			)
		)
		(property "Footprint" "antmicro-footprints:SW_KMR211NGLFS_SMD"
			(at 236.22 57.15 0)
			(effects
				(font
					(size 1.27 1.27)
					(thickness 0.15)
				)
				(justify left bottom)
				(hide yes)
			)
		)
		(property "Datasheet" "http://www.farnell.com/datasheets/2631211.pdf"
			(at 233.68 57.15 0)
			(effects
				(font
					(size 1.27 1.27)
					(thickness 0.15)
				)
				(justify left bottom)
				(hide yes)
			)
		)
		(property "Description" ""
			(at 246.38 31.75 0)
			(effects
				(font
					(size 1.27 1.27)
				)
				(hide yes)
			)
		)
		(property "MPN" "KMR211NGLFS"
			(at 249.555 38.1 90)
			(effects
				(font
					(size 1.27 1.27)
					(thickness 0.15)
				)
				(justify left)
			)
		)
		(property "Manufacturer" "C&K"
			(at 231.14 57.15 0)
			(effects
				(font
					(size 1.27 1.27)
					(thickness 0.15)
				)
				(justify left bottom)
				(hide yes)
			)
		)
		(property "Author" "Antmicro"
			(at 228.6 57.15 0)
			(effects
				(font
					(size 1.27 1.27)
					(thickness 0.15)
				)
				(justify left bottom)
				(hide yes)
			)
		)
		(property "License" "Apache-2.0"
			(at 226.06 57.15 0)
			(effects
				(font
					(size 1.27 1.27)
					(thickness 0.15)
				)
				(justify left bottom)
				(hide yes)
			)
		)
		(pin "1"
		)
		(pin "2"
		)
		(pin "3"
		)
		(pin "4"
		)
		(instances
			(project "jetson-orin-baseboard"
				(path ""
					(reference "S5")
					(unit 1)
				)
			)
		)
	)
	(symbol
		(lib_id "antmicroResistors0603:R_0R_22.4A_0603")
		(at 344.17 193.04 0)
		(unit 1)
		(exclude_from_sim no)
		(in_bom yes)
		(on_board yes)
		(dnp no)
		(property "Reference" "R178"
			(at 346.71 187.96 0)
			(effects
				(font
					(size 1.27 1.27)
				)
			)
		)
		(property "Value" "R_0R_22.4A_0603"
			(at 346.71 184.15 0)
			(effects
				(font
					(size 1.27 1.27)
					(thickness 0.15)
				)
				(hide yes)
			)
		)
		(property "Footprint" "antmicro-footprints:R_0603_1608Metric"
			(at 359.41 203.2 0)
			(effects
				(font
					(size 1.27 1.27)
					(thickness 0.15)
				)
				(justify left bottom)
				(hide yes)
			)
		)
		(property "Datasheet" "https://fscdn.rohm.com/en/products/databook/datasheet/passive/resistor/chip_resistor/pmr-jpw-e.pdf"
			(at 359.41 205.74 0)
			(effects
				(font
					(size 1.27 1.27)
					(thickness 0.15)
				)
				(justify left bottom)
				(hide yes)
			)
		)
		(property "Description" ""
			(at 344.17 193.04 0)
			(effects
				(font
					(size 1.27 1.27)
				)
				(hide yes)
			)
		)
		(property "Manufacturer" "ROHM Semiconductor"
			(at 359.41 210.82 0)
			(effects
				(font
					(size 1.27 1.27)
					(thickness 0.15)
				)
				(justify left bottom)
				(hide yes)
			)
		)
		(property "MPN" "PMR03EZPJ000"
			(at 359.41 208.28 0)
			(effects
				(font
					(size 1.27 1.27)
					(thickness 0.15)
				)
				(justify left bottom)
				(hide yes)
			)
		)
		(property "Val" "0R"
			(at 346.71 190.5 0)
			(effects
				(font
					(size 1.27 1.27)
					(thickness 0.15)
				)
			)
		)
		(property "Author" "Antmicro"
			(at 359.41 215.9 0)
			(effects
				(font
					(size 1.27 1.27)
					(thickness 0.15)
				)
				(justify left bottom)
				(hide yes)
			)
		)
		(property "License" "Apache-2.0"
			(at 359.41 218.44 0)
			(effects
				(font
					(size 1.27 1.27)
					(thickness 0.15)
				)
				(justify left bottom)
				(hide yes)
			)
		)
		(property "Max. Curr." "22.4A"
			(at 346.71 195.58 0)
			(effects
				(font
					(size 1.27 1.27)
					(thickness 0.15)
				)
			)
		)
		(property "Tolerance" "template_tolerance"
			(at 364.49 203.2 0)
			(effects
				(font
					(size 1.27 1.27)
				)
				(justify left bottom)
				(hide yes)
			)
		)
		(pin "1"
		)
		(pin "2"
		)
		(instances
			(project "jetson-orin-baseboard"
				(path ""
					(reference "R178")
					(unit 1)
				)
			)
		)
	)
	(symbol
		(lib_id "antmicropower:GND")
		(at 262.89 250.19 0)
		(unit 1)
		(exclude_from_sim no)
		(in_bom yes)
		(on_board yes)
		(dnp no)
		(property "Reference" "#PWR0372"
			(at 262.89 256.54 0)
			(effects
				(font
					(size 1.27 1.27)
				)
				(justify left bottom)
				(hide yes)
			)
		)
		(property "Value" "GND"
			(at 262.89 254 0)
			(effects
				(font
					(size 1.27 1.27)
					(thickness 0.15)
				)
			)
		)
		(property "Footprint" ""
			(at 271.78 257.81 0)
			(effects
				(font
					(size 1.27 1.27)
					(thickness 0.15)
				)
				(justify left bottom)
				(hide yes)
			)
		)
		(property "Datasheet" ""
			(at 271.78 262.89 0)
			(effects
				(font
					(size 1.27 1.27)
					(thickness 0.15)
				)
				(justify left bottom)
				(hide yes)
			)
		)
		(property "Description" ""
			(at 262.89 250.19 0)
			(effects
				(font
					(size 1.27 1.27)
				)
				(hide yes)
			)
		)
		(property "Author" "Antmicro"
			(at 271.78 257.81 0)
			(effects
				(font
					(size 1.27 1.27)
					(thickness 0.15)
				)
				(justify left bottom)
				(hide yes)
			)
		)
		(property "License" "Apache-2.0"
			(at 271.78 260.35 0)
			(effects
				(font
					(size 1.27 1.27)
					(thickness 0.15)
				)
				(justify left bottom)
				(hide yes)
			)
		)
		(pin "1"
		)
		(instances
			(project "jetson-orin-baseboard"
				(path ""
					(reference "#PWR0372")
					(unit 1)
				)
			)
		)
	)
	(symbol
		(lib_id "antmicroTVSDiodes:DF2S30FS_SOD")
		(at 166.37 167.64 270)
		(unit 1)
		(exclude_from_sim no)
		(in_bom yes)
		(on_board yes)
		(dnp no)
		(property "Reference" "D29"
			(at 167.64 168.91 90)
			(effects
				(font
					(size 1.27 1.27)
				)
				(justify left)
			)
		)
		(property "Value" "DF2S30FS_SOD"
			(at 151.13 189.23 0)
			(effects
				(font
					(size 1.27 1.27)
					(thickness 0.15)
				)
				(justify left bottom)
				(hide yes)
			)
		)
		(property "Footprint" "antmicro-footprints:SOD-923"
			(at 158.75 189.23 0)
			(effects
				(font
					(size 1.27 1.27)
					(thickness 0.15)
				)
				(justify left bottom)
				(hide yes)
			)
		)
		(property "Datasheet" "https://toshiba.semicon-storage.com/info/DF2S30FS_datasheet_en_20211216.pdf?did=11156&prodName=DF2S30FS"
			(at 156.21 189.23 0)
			(effects
				(font
					(size 1.27 1.27)
					(thickness 0.15)
				)
				(justify left bottom)
				(hide yes)
			)
		)
		(property "Description" ""
			(at 166.37 167.64 0)
			(effects
				(font
					(size 1.27 1.27)
				)
				(hide yes)
			)
		)
		(property "Manufacturer" "Toshiba"
			(at 153.67 189.23 0)
			(effects
				(font
					(size 1.27 1.27)
					(thickness 0.15)
				)
				(justify left bottom)
				(hide yes)
			)
		)
		(property "MPN" "DF2S30FS"
			(at 167.64 171.45 90)
			(effects
				(font
					(size 1.27 1.27)
					(thickness 0.15)
				)
				(justify left)
			)
		)
		(property "Author" "Antmicro"
			(at 148.59 189.23 0)
			(effects
				(font
					(size 1.27 1.27)
					(thickness 0.15)
				)
				(justify left bottom)
				(hide yes)
			)
		)
		(property "License" "Apache-2.0"
			(at 146.05 189.23 0)
			(effects
				(font
					(size 1.27 1.27)
					(thickness 0.15)
				)
				(justify left bottom)
				(hide yes)
			)
		)
		(pin "1"
		)
		(pin "2"
		)
		(instances
			(project "jetson-orin-baseboard"
				(path ""
					(reference "D29")
					(unit 1)
				)
			)
		)
	)
	(symbol
		(lib_id "antmicroPMICORControllersIdealDiodes:TPS259474ARPWR")
		(at 214.63 236.22 0)
		(unit 1)
		(exclude_from_sim no)
		(in_bom yes)
		(on_board yes)
		(dnp no)
		(property "Reference" "U48"
			(at 226.06 228.6 0)
			(effects
				(font
					(size 1.27 1.27)
					(thickness 0.15)
				)
			)
		)
		(property "Value" "TPS259474"
			(at 250.19 243.84 0)
			(effects
				(font
					(size 1.27 1.27)
					(thickness 0.15)
				)
				(justify left bottom)
				(hide yes)
			)
		)
		(property "Footprint" "antmicro-footprints:VQFN-HR-10_2x2mm"
			(at 250.19 246.38 0)
			(effects
				(font
					(size 1.27 1.27)
					(thickness 0.15)
				)
				(justify left bottom)
				(hide yes)
			)
		)
		(property "Datasheet" "https://www.ti.com/lit/ds/symlink/tps25947.pdf"
			(at 250.19 248.92 0)
			(effects
				(font
					(size 1.27 1.27)
					(thickness 0.15)
				)
				(justify left bottom)
				(hide yes)
			)
		)
		(property "Description" "Reverse Current Blocking eFuse with Input Reverse Polarity Protection, 5.5A, 23V, -40 to 125 Deg C, VQFN-HR-10"
			(at 250.19 251.46 0)
			(effects
				(font
					(size 1.27 1.27)
					(thickness 0.15)
				)
				(justify left bottom)
				(hide yes)
			)
		)
		(property "MPN" "TPS259474ARPWR"
			(at 226.06 231.14 0)
			(effects
				(font
					(size 1.27 1.27)
					(thickness 0.15)
				)
			)
		)
		(property "Manufacturer" "Texas Instruments"
			(at 250.19 254 0)
			(effects
				(font
					(size 1.27 1.27)
					(thickness 0.15)
				)
				(justify left bottom)
				(hide yes)
			)
		)
		(property "Author" "Antmicro"
			(at 250.19 256.54 0)
			(effects
				(font
					(size 1.27 1.27)
					(thickness 0.15)
				)
				(justify left bottom)
				(hide yes)
			)
		)
		(property "License" "Apache-2.0"
			(at 250.19 259.08 0)
			(effects
				(font
					(size 1.27 1.27)
					(thickness 0.15)
				)
				(justify left bottom)
				(hide yes)
			)
		)
		(pin "1"
		)
		(pin "10"
		)
		(pin "9"
		)
		(pin "7"
		)
		(pin "8"
		)
		(pin "3"
		)
		(pin "4"
		)
		(pin "2"
		)
		(pin "6"
		)
		(pin "5"
		)
		(instances
			(project ""
				(path ""
					(reference "U48")
					(unit 1)
				)
			)
		)
	)
	(symbol
		(lib_id "antmicropower:GND")
		(at 233.68 120.65 0)
		(unit 1)
		(exclude_from_sim no)
		(in_bom yes)
		(on_board yes)
		(dnp no)
		(property "Reference" "#PWR0350"
			(at 233.68 127 0)
			(effects
				(font
					(size 1.27 1.27)
				)
				(justify left bottom)
				(hide yes)
			)
		)
		(property "Value" "GND"
			(at 233.68 124.46 0)
			(effects
				(font
					(size 1.27 1.27)
					(thickness 0.15)
				)
			)
		)
		(property "Footprint" ""
			(at 242.57 128.27 0)
			(effects
				(font
					(size 1.27 1.27)
					(thickness 0.15)
				)
				(justify left bottom)
				(hide yes)
			)
		)
		(property "Datasheet" ""
			(at 242.57 133.35 0)
			(effects
				(font
					(size 1.27 1.27)
					(thickness 0.15)
				)
				(justify left bottom)
				(hide yes)
			)
		)
		(property "Description" ""
			(at 233.68 120.65 0)
			(effects
				(font
					(size 1.27 1.27)
				)
				(hide yes)
			)
		)
		(property "Author" "Antmicro"
			(at 242.57 128.27 0)
			(effects
				(font
					(size 1.27 1.27)
					(thickness 0.15)
				)
				(justify left bottom)
				(hide yes)
			)
		)
		(property "License" "Apache-2.0"
			(at 242.57 130.81 0)
			(effects
				(font
					(size 1.27 1.27)
					(thickness 0.15)
				)
				(justify left bottom)
				(hide yes)
			)
		)
		(pin "1"
		)
		(instances
			(project "jetson-orin-baseboard"
				(path ""
					(reference "#PWR0350")
					(unit 1)
				)
			)
		)
	)
	(symbol
		(lib_id "antmicropower:GND")
		(at 124.46 34.29 0)
		(unit 1)
		(exclude_from_sim no)
		(in_bom yes)
		(on_board yes)
		(dnp no)
		(property "Reference" "#PWR0262"
			(at 124.46 40.64 0)
			(effects
				(font
					(size 1.27 1.27)
				)
				(justify left bottom)
				(hide yes)
			)
		)
		(property "Value" "GND"
			(at 124.46 38.1 0)
			(effects
				(font
					(size 1.27 1.27)
					(thickness 0.15)
				)
			)
		)
		(property "Footprint" ""
			(at 133.35 41.91 0)
			(effects
				(font
					(size 1.27 1.27)
					(thickness 0.15)
				)
				(justify left bottom)
				(hide yes)
			)
		)
		(property "Datasheet" ""
			(at 133.35 46.99 0)
			(effects
				(font
					(size 1.27 1.27)
					(thickness 0.15)
				)
				(justify left bottom)
				(hide yes)
			)
		)
		(property "Description" ""
			(at 124.46 34.29 0)
			(effects
				(font
					(size 1.27 1.27)
				)
				(hide yes)
			)
		)
		(property "Author" "Antmicro"
			(at 133.35 41.91 0)
			(effects
				(font
					(size 1.27 1.27)
					(thickness 0.15)
				)
				(justify left bottom)
				(hide yes)
			)
		)
		(property "License" "Apache-2.0"
			(at 133.35 44.45 0)
			(effects
				(font
					(size 1.27 1.27)
					(thickness 0.15)
				)
				(justify left bottom)
				(hide yes)
			)
		)
		(pin "1"
		)
		(instances
			(project "jetson-orin-baseboard"
				(path ""
					(reference "#PWR0262")
					(unit 1)
				)
			)
		)
	)
	(symbol
		(lib_id "antmicroCapacitors0402:C_100n_0402")
		(at 146.05 171.45 90)
		(unit 1)
		(exclude_from_sim no)
		(in_bom yes)
		(on_board yes)
		(dnp no)
		(property "Reference" "C50"
			(at 147.955 167.64 90)
			(effects
				(font
					(size 1.27 1.27)
				)
				(justify right)
			)
		)
		(property "Value" "C_100n_0402"
			(at 156.21 151.13 0)
			(effects
				(font
					(size 1.27 1.27)
					(thickness 0.15)
				)
				(justify left bottom)
				(hide yes)
			)
		)
		(property "Footprint" "antmicro-footprints:C_0402_1005Metric"
			(at 158.75 151.13 0)
			(effects
				(font
					(size 1.27 1.27)
					(thickness 0.15)
				)
				(justify left bottom)
				(hide yes)
			)
		)
		(property "Datasheet" "https://www.murata.com/products/productdetail?partno=GRM155R61H104KE14%23"
			(at 161.29 151.13 0)
			(effects
				(font
					(size 1.27 1.27)
					(thickness 0.15)
				)
				(justify left bottom)
				(hide yes)
			)
		)
		(property "Description" ""
			(at 146.05 171.45 0)
			(effects
				(font
					(size 1.27 1.27)
				)
				(hide yes)
			)
		)
		(property "Manufacturer" "Murata"
			(at 166.37 151.13 0)
			(effects
				(font
					(size 1.27 1.27)
					(thickness 0.15)
				)
				(justify left bottom)
				(hide yes)
			)
		)
		(property "MPN" "GRM155R61H104KE14D"
			(at 163.83 151.13 0)
			(effects
				(font
					(size 1.27 1.27)
					(thickness 0.15)
				)
				(justify left bottom)
				(hide yes)
			)
		)
		(property "Val" "100n"
			(at 147.955 170.18 90)
			(effects
				(font
					(size 1.27 1.27)
					(thickness 0.15)
				)
				(justify right)
			)
		)
		(property "License" "Apache-2.0"
			(at 168.91 151.13 0)
			(effects
				(font
					(size 1.27 1.27)
					(thickness 0.15)
				)
				(justify left bottom)
				(hide yes)
			)
		)
		(property "Author" "Antmicro"
			(at 171.45 151.13 0)
			(effects
				(font
					(size 1.27 1.27)
					(thickness 0.15)
				)
				(justify left bottom)
				(hide yes)
			)
		)
		(property "Voltage" "50V"
			(at 173.99 151.13 0)
			(effects
				(font
					(size 1.27 1.27)
				)
				(justify left bottom)
				(hide yes)
			)
		)
		(property "Dielectric" "X5R"
			(at 176.53 151.13 0)
			(effects
				(font
					(size 1.27 1.27)
				)
				(justify left bottom)
				(hide yes)
			)
		)
		(pin "1"
		)
		(pin "2"
		)
		(instances
			(project "jetson-orin-baseboard"
				(path ""
					(reference "C50")
					(unit 1)
				)
			)
		)
	)
	(symbol
		(lib_id "antmicropower:GND")
		(at 189.23 213.36 0)
		(unit 1)
		(exclude_from_sim no)
		(in_bom yes)
		(on_board yes)
		(dnp no)
		(property "Reference" "#PWR0323"
			(at 189.23 219.71 0)
			(effects
				(font
					(size 1.27 1.27)
				)
				(justify left bottom)
				(hide yes)
			)
		)
		(property "Value" "GND"
			(at 189.23 217.17 0)
			(effects
				(font
					(size 1.27 1.27)
					(thickness 0.15)
				)
			)
		)
		(property "Footprint" ""
			(at 198.12 220.98 0)
			(effects
				(font
					(size 1.27 1.27)
					(thickness 0.15)
				)
				(justify left bottom)
				(hide yes)
			)
		)
		(property "Datasheet" ""
			(at 198.12 226.06 0)
			(effects
				(font
					(size 1.27 1.27)
					(thickness 0.15)
				)
				(justify left bottom)
				(hide yes)
			)
		)
		(property "Description" ""
			(at 189.23 213.36 0)
			(effects
				(font
					(size 1.27 1.27)
				)
				(hide yes)
			)
		)
		(property "Author" "Antmicro"
			(at 198.12 220.98 0)
			(effects
				(font
					(size 1.27 1.27)
					(thickness 0.15)
				)
				(justify left bottom)
				(hide yes)
			)
		)
		(property "License" "Apache-2.0"
			(at 198.12 223.52 0)
			(effects
				(font
					(size 1.27 1.27)
					(thickness 0.15)
				)
				(justify left bottom)
				(hide yes)
			)
		)
		(pin "1"
		)
		(instances
			(project "jetson-orin-baseboard"
				(path ""
					(reference "#PWR0323")
					(unit 1)
				)
			)
		)
	)
	(symbol
		(lib_id "antmicroCapacitors0402:C_10u_0402")
		(at 60.96 80.01 90)
		(unit 1)
		(exclude_from_sim no)
		(in_bom yes)
		(on_board yes)
		(dnp no)
		(fields_autoplaced yes)
		(property "Reference" "C116"
			(at 63.5 76.1936 90)
			(effects
				(font
					(size 1.27 1.27)
					(thickness 0.15)
				)
				(justify right)
			)
		)
		(property "Value" "C_10u_0402"
			(at 71.12 59.69 0)
			(effects
				(font
					(size 1.27 1.27)
					(thickness 0.15)
				)
				(justify left bottom)
				(hide yes)
			)
		)
		(property "Footprint" "antmicro-footprints:C_0402_1005Metric"
			(at 73.66 59.69 0)
			(effects
				(font
					(size 1.27 1.27)
					(thickness 0.15)
				)
				(justify left bottom)
				(hide yes)
			)
		)
		(property "Datasheet" "https://www.yageo.com/en/Chart/Download/pdf/CC0402MRX5R5BB106"
			(at 76.2 59.69 0)
			(effects
				(font
					(size 1.27 1.27)
					(thickness 0.15)
				)
				(justify left bottom)
				(hide yes)
			)
		)
		(property "Description" ""
			(at 60.96 80.01 0)
			(effects
				(font
					(size 1.27 1.27)
				)
				(hide yes)
			)
		)
		(property "MPN" "CC0402MRX5R5BB106"
			(at 78.74 59.69 0)
			(effects
				(font
					(size 1.27 1.27)
					(thickness 0.15)
				)
				(justify left bottom)
				(hide yes)
			)
		)
		(property "Manufacturer" "YAGEO"
			(at 81.28 59.69 0)
			(effects
				(font
					(size 1.27 1.27)
					(thickness 0.15)
				)
				(justify left bottom)
				(hide yes)
			)
		)
		(property "License" "Apache-2.0"
			(at 83.82 59.69 0)
			(effects
				(font
					(size 1.27 1.27)
					(thickness 0.15)
				)
				(justify left bottom)
				(hide yes)
			)
		)
		(property "Author" "Antmicro"
			(at 86.36 59.69 0)
			(effects
				(font
					(size 1.27 1.27)
					(thickness 0.15)
				)
				(justify left bottom)
				(hide yes)
			)
		)
		(property "Val" "10u"
			(at 63.5 78.7336 90)
			(effects
				(font
					(size 1.27 1.27)
					(thickness 0.15)
				)
				(justify right)
			)
		)
		(property "Voltage" ""
			(at 88.9 59.69 0)
			(effects
				(font
					(size 1.27 1.27)
				)
				(justify left bottom)
				(hide yes)
			)
		)
		(property "Dielectric" ""
			(at 91.44 59.69 0)
			(effects
				(font
					(size 1.27 1.27)
				)
				(justify left bottom)
				(hide yes)
			)
		)
		(pin "1"
		)
		(pin "2"
		)
		(instances
			(project "jetson-orin-baseboard"
				(path ""
					(reference "C116")
					(unit 1)
				)
			)
		)
	)
	(symbol
		(lib_id "antmicroCapacitors0402:C_10u_0402")
		(at 299.72 72.39 270)
		(unit 1)
		(exclude_from_sim no)
		(in_bom yes)
		(on_board yes)
		(dnp no)
		(property "Reference" "C83"
			(at 301.625 73.66 90)
			(effects
				(font
					(size 1.27 1.27)
					(thickness 0.15)
				)
				(justify left)
			)
		)
		(property "Value" "C_10u_0402"
			(at 289.56 92.71 0)
			(effects
				(font
					(size 1.27 1.27)
					(thickness 0.15)
				)
				(justify left bottom)
				(hide yes)
			)
		)
		(property "Footprint" "antmicro-footprints:C_0402_1005Metric"
			(at 287.02 92.71 0)
			(effects
				(font
					(size 1.27 1.27)
					(thickness 0.15)
				)
				(justify left bottom)
				(hide yes)
			)
		)
		(property "Datasheet" "https://www.yageo.com/en/Chart/Download/pdf/CC0402MRX5R5BB106"
			(at 284.48 92.71 0)
			(effects
				(font
					(size 1.27 1.27)
					(thickness 0.15)
				)
				(justify left bottom)
				(hide yes)
			)
		)
		(property "Description" ""
			(at 299.72 72.39 0)
			(effects
				(font
					(size 1.27 1.27)
				)
				(hide yes)
			)
		)
		(property "MPN" "CC0402MRX5R5BB106"
			(at 281.94 92.71 0)
			(effects
				(font
					(size 1.27 1.27)
					(thickness 0.15)
				)
				(justify left bottom)
				(hide yes)
			)
		)
		(property "Manufacturer" "YAGEO"
			(at 279.4 92.71 0)
			(effects
				(font
					(size 1.27 1.27)
					(thickness 0.15)
				)
				(justify left bottom)
				(hide yes)
			)
		)
		(property "License" "Apache-2.0"
			(at 276.86 92.71 0)
			(effects
				(font
					(size 1.27 1.27)
					(thickness 0.15)
				)
				(justify left bottom)
				(hide yes)
			)
		)
		(property "Author" "Antmicro"
			(at 274.32 92.71 0)
			(effects
				(font
					(size 1.27 1.27)
					(thickness 0.15)
				)
				(justify left bottom)
				(hide yes)
			)
		)
		(property "Val" "10u"
			(at 301.625 76.2 90)
			(effects
				(font
					(size 1.27 1.27)
					(thickness 0.15)
				)
				(justify left)
			)
		)
		(property "Voltage" ""
			(at 271.78 92.71 0)
			(effects
				(font
					(size 1.27 1.27)
				)
				(justify left bottom)
				(hide yes)
			)
		)
		(property "Dielectric" ""
			(at 269.24 92.71 0)
			(effects
				(font
					(size 1.27 1.27)
				)
				(justify left bottom)
				(hide yes)
			)
		)
		(pin "1"
		)
		(pin "2"
		)
		(instances
			(project "jetson-orin-baseboard"
				(path ""
					(reference "C83")
					(unit 1)
				)
			)
		)
	)
	(symbol
		(lib_id "antmicroLEDIndicationDiscrete:LED_G_0603_LTST-C190GKT")
		(at 162.56 254 90)
		(unit 1)
		(exclude_from_sim no)
		(in_bom yes)
		(on_board yes)
		(dnp no)
		(property "Reference" "D62"
			(at 163.83 250.19 90)
			(effects
				(font
					(size 1.27 1.27)
				)
				(justify right)
			)
		)
		(property "Value" "LED_G_0603_LTST-C190GKT"
			(at 170.18 231.14 0)
			(effects
				(font
					(size 1.27 1.27)
					(thickness 0.15)
				)
				(justify left bottom)
				(hide yes)
			)
		)
		(property "Footprint" "antmicro-footprints:LED_0603_1608Metric_G"
			(at 172.72 231.14 0)
			(effects
				(font
					(size 1.27 1.27)
					(thickness 0.15)
				)
				(justify left bottom)
				(hide yes)
			)
		)
		(property "Datasheet" "https://media.digikey.com/pdf/Data%20Sheets/Lite-On%20PDFs/LTST-C190GKT.pdf"
			(at 175.26 231.14 0)
			(effects
				(font
					(size 1.27 1.27)
					(thickness 0.15)
				)
				(justify left bottom)
				(hide yes)
			)
		)
		(property "Description" ""
			(at 162.56 254 0)
			(effects
				(font
					(size 1.27 1.27)
				)
				(hide yes)
			)
		)
		(property "MPN" "LTST-C190GKT"
			(at 177.8 231.14 0)
			(effects
				(font
					(size 1.27 1.27)
					(thickness 0.15)
				)
				(justify left bottom)
				(hide yes)
			)
		)
		(property "Manufacturer" "Lite-On"
			(at 180.34 231.14 0)
			(effects
				(font
					(size 1.27 1.27)
					(thickness 0.15)
				)
				(justify left bottom)
				(hide yes)
			)
		)
		(property "Author" "Antmicro"
			(at 182.88 231.14 0)
			(effects
				(font
					(size 1.27 1.27)
					(thickness 0.15)
				)
				(justify left bottom)
				(hide yes)
			)
		)
		(property "License" "Apache-2.0"
			(at 185.42 231.14 0)
			(effects
				(font
					(size 1.27 1.27)
					(thickness 0.15)
				)
				(justify left bottom)
				(hide yes)
			)
		)
		(property "Color" "Green"
			(at 163.83 252.73 90)
			(effects
				(font
					(size 1.27 1.27)
				)
				(justify right)
			)
		)
		(pin "1"
		)
		(pin "2"
		)
		(instances
			(project "jetson-orin-baseboard"
				(path ""
					(reference "D62")
					(unit 1)
				)
			)
		)
	)
	(symbol
		(lib_id "antmicroTransistorsFETsMOSFETsSingle:PJE138K")
		(at 36.83 71.12 0)
		(unit 1)
		(exclude_from_sim no)
		(in_bom yes)
		(on_board yes)
		(dnp no)
		(property "Reference" "Q7"
			(at 36.195 63.5 0)
			(effects
				(font
					(size 1.27 1.27)
					(thickness 0.15)
				)
				(justify left bottom)
			)
		)
		(property "Value" "PJE138K"
			(at 59.69 80.01 0)
			(effects
				(font
					(size 1.27 1.27)
					(thickness 0.15)
				)
				(justify left bottom)
				(hide yes)
			)
		)
		(property "Footprint" "antmicro-footprints:SOT-523"
			(at 59.69 82.55 0)
			(effects
				(font
					(size 1.27 1.27)
					(thickness 0.15)
				)
				(justify left bottom)
				(hide yes)
			)
		)
		(property "Datasheet" "https://www.mouser.com/datasheet/2/1057/PJE138K-1876698.pdf"
			(at 59.69 85.09 0)
			(effects
				(font
					(size 1.27 1.27)
					(thickness 0.15)
				)
				(justify left bottom)
				(hide yes)
			)
		)
		(property "Description" ""
			(at 36.83 71.12 0)
			(effects
				(font
					(size 1.27 1.27)
				)
				(hide yes)
			)
		)
		(property "MPN" "PJE138K_R1_00001"
			(at 20.32 66.04 0)
			(effects
				(font
					(size 1.27 1.27)
					(thickness 0.15)
				)
				(justify left bottom)
			)
		)
		(property "Manufacturer" "PANJIT"
			(at 59.69 90.17 0)
			(effects
				(font
					(size 1.27 1.27)
					(thickness 0.15)
				)
				(justify left bottom)
				(hide yes)
			)
		)
		(property "Author" "Antmicro"
			(at 59.69 92.71 0)
			(effects
				(font
					(size 1.27 1.27)
					(thickness 0.15)
				)
				(justify left bottom)
				(hide yes)
			)
		)
		(property "License" "Apache-2.0"
			(at 59.69 95.25 0)
			(effects
				(font
					(size 1.27 1.27)
					(thickness 0.15)
				)
				(justify left bottom)
				(hide yes)
			)
		)
		(pin "2"
		)
		(pin "3"
		)
		(pin "1"
		)
		(instances
			(project "jetson-orin-baseboard"
				(path ""
					(reference "Q7")
					(unit 1)
				)
			)
		)
	)
	(symbol
		(lib_id "antmicropower:GND")
		(at 106.68 68.58 0)
		(unit 1)
		(exclude_from_sim no)
		(in_bom yes)
		(on_board yes)
		(dnp no)
		(property "Reference" "#PWR0260"
			(at 106.68 74.93 0)
			(effects
				(font
					(size 1.27 1.27)
				)
				(justify left bottom)
				(hide yes)
			)
		)
		(property "Value" "GND"
			(at 106.68 72.39 0)
			(effects
				(font
					(size 1.27 1.27)
					(thickness 0.15)
				)
			)
		)
		(property "Footprint" ""
			(at 115.57 76.2 0)
			(effects
				(font
					(size 1.27 1.27)
					(thickness 0.15)
				)
				(justify left bottom)
				(hide yes)
			)
		)
		(property "Datasheet" ""
			(at 115.57 81.28 0)
			(effects
				(font
					(size 1.27 1.27)
					(thickness 0.15)
				)
				(justify left bottom)
				(hide yes)
			)
		)
		(property "Description" ""
			(at 106.68 68.58 0)
			(effects
				(font
					(size 1.27 1.27)
				)
				(hide yes)
			)
		)
		(property "Author" "Antmicro"
			(at 115.57 76.2 0)
			(effects
				(font
					(size 1.27 1.27)
					(thickness 0.15)
				)
				(justify left bottom)
				(hide yes)
			)
		)
		(property "License" "Apache-2.0"
			(at 115.57 78.74 0)
			(effects
				(font
					(size 1.27 1.27)
					(thickness 0.15)
				)
				(justify left bottom)
				(hide yes)
			)
		)
		(pin "1"
		)
		(instances
			(project "jetson-orin-baseboard"
				(path ""
					(reference "#PWR0260")
					(unit 1)
				)
			)
		)
	)
	(symbol
		(lib_id "antmicroTVSDiodes:TPD1E0B04_XDFN-2")
		(at 36.83 41.91 90)
		(unit 1)
		(exclude_from_sim no)
		(in_bom yes)
		(on_board yes)
		(dnp no)
		(property "Reference" "D60"
			(at 34.925 38.1 90)
			(effects
				(font
					(size 1.27 1.27)
				)
				(justify left)
			)
		)
		(property "Value" "TPD1E0B04_XDFN-2"
			(at 46.99 26.67 0)
			(effects
				(font
					(size 1.27 1.27)
					(thickness 0.15)
				)
				(justify left bottom)
				(hide yes)
			)
		)
		(property "Footprint" "antmicro-footprints:XDFN-2_1x0.60mm"
			(at 41.91 26.67 0)
			(effects
				(font
					(size 1.27 1.27)
					(thickness 0.15)
				)
				(justify left bottom)
				(hide yes)
			)
		)
		(property "Datasheet" "https://www.ti.com/general/docs/suppproductinfo.tsp?distId=26&gotoUrl=https://www.ti.com/lit/gpn/tpd1e0b04"
			(at 44.45 26.67 0)
			(effects
				(font
					(size 1.27 1.27)
					(thickness 0.15)
				)
				(justify left bottom)
				(hide yes)
			)
		)
		(property "Description" ""
			(at 36.83 41.91 0)
			(effects
				(font
					(size 1.27 1.27)
				)
				(hide yes)
			)
		)
		(property "Manufacturer" "Texas Instruments"
			(at 49.53 26.67 0)
			(effects
				(font
					(size 1.27 1.27)
					(thickness 0.15)
				)
				(justify left bottom)
				(hide yes)
			)
		)
		(property "MPN" "TPD1E0B04DPYR"
			(at 34.925 40.64 90)
			(effects
				(font
					(size 1.27 1.27)
					(thickness 0.15)
				)
				(justify left)
			)
		)
		(property "Author" "Antmicro"
			(at 52.07 26.67 0)
			(effects
				(font
					(size 1.27 1.27)
					(thickness 0.15)
				)
				(justify left bottom)
				(hide yes)
			)
		)
		(property "License" "Apache-2.0"
			(at 54.61 26.67 0)
			(effects
				(font
					(size 1.27 1.27)
					(thickness 0.15)
				)
				(justify left bottom)
				(hide yes)
			)
		)
		(pin "1"
		)
		(pin "2"
		)
		(instances
			(project "jetson-orin-baseboard"
				(path ""
					(reference "D60")
					(unit 1)
				)
			)
		)
	)
)
